G04 ================== begin FILE IDENTIFICATION RECORD ==================*
G04 Layout Name:  F:/<user>/2022/FB/R4006-TIMING/brd/gerber-3/R4006-B0001-02_R01.brd*
G04 Film Name:    R4006-B0001-02_R01_BSM*
G04 File Format:  Gerber RS274X*
G04 File Origin:  Cadence Allegro 17.2-S079*
G04 Origin Date:  Fri Feb 25 18:14:43 2022*
G04 *
G04 Layer:  PACKAGE GEOMETRY/SOLDERMASK_BOTTOM*
G04 Layer:  BOARD GEOMETRY/SOLDERMASK_BOTTOM*
G04 Layer:  BOARD GEOMETRY/OUTLINE*
G04 Layer:  PIN/SOLDERMASK_BOTTOM*
G04 Layer:  VIA CLASS/SOLDERMASK_BOTTOM*
G04 Layer:  MANUFACTURING/CELESTICA_LEGEND*
G04 *
G04 Offset:    (0.00 0.00)*
G04 Mirror:    No*
G04 Mode:      Positive*
G04 Rotation:  0*
G04 FullContactRelief:  No*
G04 UndefLineWidth:     40.00*
G04 ================== end FILE IDENTIFICATION RECORD ====================*
%FSLAX55Y55*MOIN*%
%IR0*IPPOS*OFA0.00000B0.00000*MIA0B0*SFA1.00000B1.00000*%
%ADD27R,.032X.13*%
%ADD10C,.012*%
%ADD12C,.014*%
%ADD45C,.061*%
%ADD37R,.112X.089*%
%ADD13C,.034*%
%ADD26R,.032X.169*%
%ADD36R,.049X.108*%
%ADD16C,.09*%
%ADD15C,.028*%
%ADD35C,.029*%
%ADD11C,.094*%
%ADD24C,.11*%
%ADD21C,.12*%
%ADD32R,.024X.051*%
%ADD31C,.202*%
%ADD39R,.043X.061*%
%ADD23C,.104*%
%ADD20R,.064X.022*%
%ADD30R,.017X.042*%
%ADD19R,.028X.032*%
%ADD17R,.032X.028*%
%ADD38R,.019X.016*%
%ADD41C,.108*%
%ADD40R,.047X.061*%
%ADD22R,.038X.034*%
%ADD14C,.135*%
%ADD33R,.058X.042*%
%ADD25R,.034X.038*%
%ADD44O,.079X.052*%
%ADD43C,.128*%
%ADD29R,.042X.058*%
%ADD34R,.059X.043*%
%ADD28R,.069X.024*%
%ADD42R,.108X.108*%
%ADD18O,.079X.039*%
%ADD46C,.01*%
%ADD47C,.005*%
%ADD48C,.04*%
G75*
%LPD*%
G75*
G36*
G01X56043Y53530D02*
Y21660D01*
X55126Y20743D01*
X7138D01*
X3827D01*
X3033Y21537D01*
Y53530D01*
X56043D01*
G37*
G36*
G01X50000Y433661D02*
Y353150D01*
X3937D01*
X3012D01*
Y391790D01*
Y433747D01*
X3854Y434589D01*
X50000D01*
Y433661D01*
G37*
G36*
G01X155767Y106043D02*
G03I-12200J0D01*
G37*
G36*
G01X158267Y268043D02*
G03I-12200J0D01*
G37*
G36*
G01X179200Y-19D02*
X310200D01*
X312200Y1981D01*
Y22231D01*
X177200D01*
Y1981D01*
X179200Y-19D01*
G37*
G36*
G01X280767Y112143D02*
G03I-12200J0D01*
G37*
G36*
G01Y255943D02*
G03I-12200J0D01*
G37*
G36*
G01X563550Y236343D02*
X565450D01*
Y232657D01*
X563550D01*
Y236343D01*
G37*
G36*
G01X620500Y54134D02*
X620551D01*
Y90157D01*
X657017D01*
Y54005D01*
X656242Y53230D01*
X620500D01*
Y54134D01*
G37*
G36*
G01X620551Y392520D02*
X656980D01*
Y433915D01*
X656403Y434492D01*
X620551D01*
Y433661D01*
Y392520D01*
G37*
G36*
G01X41528Y36811D02*
G03I-12000J0D01*
G37*
G36*
G01Y373031D02*
G03I-12000J0D01*
G37*
G36*
G01X652039Y65354D02*
G03I-12000J0D01*
G37*
G36*
G01Y417835D02*
G03I-12000J0D01*
G37*
G36*
G01X163800Y404500D02*
Y401700D01*
X162400D01*
Y404500D01*
X163800D01*
G37*
G36*
G01X336100Y393300D02*
Y396100D01*
X337500D01*
Y393300D01*
X336100D01*
G37*
G36*
G01X562600Y216300D02*
Y217700D01*
X565400D01*
Y216300D01*
X562600D01*
G37*
G54D10*
X8878Y21717D03*
X4878D03*
X4000Y25619D03*
Y29619D03*
Y33619D03*
Y37619D03*
Y41619D03*
Y45619D03*
Y49619D03*
Y281619D03*
Y285619D03*
Y289619D03*
Y293619D03*
Y297619D03*
Y301619D03*
Y305619D03*
Y309619D03*
Y313619D03*
Y337619D03*
Y341619D03*
Y345619D03*
Y349619D03*
Y353619D03*
Y357619D03*
Y361619D03*
Y365619D03*
Y369619D03*
Y373619D03*
Y377619D03*
Y381619D03*
Y385619D03*
Y389619D03*
Y393619D03*
Y397619D03*
Y401619D03*
Y405619D03*
Y409619D03*
Y413619D03*
Y417619D03*
Y421619D03*
Y425619D03*
Y429619D03*
X4413Y433598D03*
X8413D03*
X24878Y21717D03*
X20878D03*
X16878D03*
X12878D03*
X12413Y433598D03*
X16413D03*
X20413D03*
X24413D03*
X28413D03*
X44878Y21717D03*
X40878D03*
X36878D03*
X32878D03*
X28878D03*
X32413Y433598D03*
X36413D03*
X40413D03*
X44413D03*
X55055Y25073D03*
X52878Y21717D03*
X48878D03*
X55055Y41073D03*
Y37073D03*
Y33073D03*
Y29073D03*
X61463Y54048D03*
X57859Y52313D03*
X55558Y49041D03*
X55055Y45073D03*
X48413Y433598D03*
X52413D03*
X56413D03*
X60413D03*
X77460Y54197D03*
X73460D03*
X69460D03*
X65460D03*
X79248Y266100D03*
X73600Y252500D03*
X67000Y283100D03*
X68600Y274000D03*
X75500Y282500D03*
X63800Y274000D03*
X76700Y357500D03*
X67100D03*
X73500D03*
X70300D03*
X68413Y433598D03*
X72413D03*
X76413D03*
X80413D03*
X64413D03*
X97460Y54197D03*
X93460D03*
X89460D03*
X85460D03*
X81460D03*
X88300Y163900D03*
X86800Y230000D03*
X85600Y263700D03*
X98000Y420000D03*
X90000Y420500D03*
X85500D03*
X84413Y433598D03*
X88413D03*
X92413D03*
X96413D03*
X113460Y54197D03*
X109460D03*
X105460D03*
X101460D03*
X113700Y382500D03*
X104100D03*
X110500D03*
X107300D03*
X104413Y433598D03*
X108413D03*
X112413D03*
X100413D03*
X132920Y51926D03*
X129450Y53917D03*
X125460Y54197D03*
X121460D03*
X117460D03*
X131500Y290500D03*
X116413Y433598D03*
X120413D03*
X124413D03*
X128413D03*
X132413D03*
X135299Y24509D03*
X150163Y21717D03*
X146163D03*
X142163D03*
X138163D03*
X135299Y28509D03*
Y32509D03*
Y36509D03*
Y40509D03*
Y44509D03*
X134977Y48496D03*
X144000Y62500D03*
X138500Y75000D03*
X145900Y75200D03*
X136000Y290500D03*
X138250Y372250D03*
X140413Y433598D03*
X144413D03*
X148413D03*
X136413D03*
X158163Y21717D03*
X154163D03*
X158795Y25667D03*
Y41667D03*
Y37667D03*
Y33667D03*
Y29667D03*
X160736Y49309D03*
X159112Y45654D03*
X163543Y52159D03*
X151840Y79935D03*
X153500Y390500D03*
X167100Y405600D03*
X152413Y433598D03*
X156413D03*
X160413D03*
X164413D03*
X180341Y47225D03*
X178196Y50601D03*
X168413Y433598D03*
X172413D03*
X176413D03*
X180413D03*
X184413D03*
X191535Y28900D03*
X201950Y29050D03*
X187598Y36900D03*
X189500Y33000D03*
X186000D03*
X187598Y28900D03*
X191535Y41200D03*
X198135Y36500D03*
X200413Y433598D03*
X188413D03*
X192413D03*
X196413D03*
X210500Y30500D03*
X208300Y289500D03*
X217300D03*
X212800D03*
X209660Y331500D03*
X204413Y433598D03*
X208413D03*
X212413D03*
X216413D03*
X220413D03*
X232700Y29100D03*
X221800Y289500D03*
X224500Y302000D03*
X224413Y433598D03*
X228413D03*
X232413D03*
X236413D03*
X254527Y28900D03*
X244619D03*
X254527Y33900D03*
X250222Y76300D03*
X247022D03*
X240508D03*
Y66700D03*
X243822Y76300D03*
X253422D03*
X240508Y69900D03*
Y73100D03*
X240413Y433598D03*
X244413D03*
X248413D03*
X252413D03*
X264339Y35300D03*
Y38500D03*
Y32100D03*
X264304Y28900D03*
X272309D03*
X264339Y41700D03*
X263300Y52200D03*
X269907Y76300D03*
X266707D03*
X263507D03*
X256413Y433598D03*
X260413D03*
X264413D03*
X268413D03*
X272413D03*
X280087Y35300D03*
Y38500D03*
Y41700D03*
Y32100D03*
X280052Y28900D03*
X288057D03*
X285055Y76300D03*
X281855D03*
X288255D03*
X273107D03*
X278655D03*
X284500Y181100D03*
Y184300D03*
Y187500D03*
X283400Y198700D03*
X280200D03*
X277000D03*
X286600D03*
X284500Y190700D03*
X286151Y329500D03*
X289600Y330100D03*
X288413Y433598D03*
X284413D03*
X280413D03*
X276413D03*
X295835Y35300D03*
Y38500D03*
Y41700D03*
Y32100D03*
X295800Y28900D03*
X295835Y44900D03*
Y48100D03*
X298726Y43529D03*
Y49471D03*
X298700Y327000D03*
Y323500D03*
X293200Y329500D03*
X304413Y433598D03*
X300413D03*
X296413D03*
X292413D03*
X307708Y28900D03*
X321402Y54197D03*
X317402D03*
X314763Y85237D03*
X312500Y87500D03*
X310237Y89763D03*
X317025Y82975D03*
X319510Y190299D03*
X322710D03*
X322200Y320500D03*
Y325000D03*
X310600Y330500D03*
Y335000D03*
X322200Y338500D03*
X324413Y433598D03*
X320413D03*
X316413D03*
X312413D03*
X308413D03*
X329402Y54197D03*
X325402D03*
X337402D03*
X341402D03*
X333402D03*
X338599Y108500D03*
X341799D03*
X337500Y113000D03*
Y122600D03*
Y116200D03*
Y119400D03*
X329110Y190299D03*
X325910D03*
X340413Y433598D03*
X336413D03*
X332413D03*
X328413D03*
X345402Y54197D03*
X349402D03*
X353402D03*
X357402D03*
X359300Y92000D03*
X348199Y108500D03*
X348264Y104707D03*
X357864D03*
X344999Y108500D03*
X351464Y104707D03*
X354664D03*
X352300Y175000D03*
X345301Y196299D03*
Y186699D03*
Y193099D03*
Y189899D03*
X354850Y276100D03*
X354800Y285600D03*
Y289800D03*
X355000Y332500D03*
Y328000D03*
X356413Y433598D03*
X352413D03*
X348413D03*
X344413D03*
X369402Y54197D03*
X373402D03*
X377402D03*
X361402D03*
X365402D03*
X373500Y78000D03*
X368900Y92000D03*
X373500Y94000D03*
X365700Y92000D03*
X362500D03*
X365101Y191559D03*
Y188359D03*
Y194759D03*
Y185159D03*
X375500Y350500D03*
X376413Y433598D03*
X372413D03*
X368413D03*
X364413D03*
X360413D03*
X381402Y54197D03*
X385402D03*
X389402D03*
X393402D03*
X380500Y77400D03*
X380400Y81600D03*
X390000Y100500D03*
X383128Y178372D03*
X388500Y400000D03*
X393500D03*
X393000Y418500D03*
X392413Y433598D03*
X388413D03*
X384413D03*
X380413D03*
X397402Y54197D03*
X401402D03*
X405402D03*
X409402D03*
X409200Y100500D03*
X398450Y116099D03*
X408050D03*
X401650D03*
X404850D03*
X398500Y400000D03*
X403000Y418500D03*
X398000D03*
X408413Y433598D03*
X404413D03*
X400413D03*
X396413D03*
X417402Y54197D03*
X421402D03*
X425402D03*
X429402D03*
X413402D03*
X413622Y75000D03*
X414000Y419000D03*
X422337Y424000D03*
X416800D03*
X428413Y433598D03*
X424413D03*
X420413D03*
X416413D03*
X412413D03*
X433402Y54197D03*
X437402D03*
X441402D03*
X445402D03*
X444050Y116599D03*
X434450D03*
X437650D03*
X440850D03*
X446500Y289500D03*
X439500Y337892D03*
X442500Y336089D03*
X439500Y341500D03*
X443000Y386500D03*
Y401500D03*
Y396500D03*
X432000D03*
X444000Y416500D03*
X444413Y433598D03*
X440413D03*
X436413D03*
X432413D03*
X449402Y54197D03*
X453402D03*
X457402D03*
X461402D03*
X450930Y122167D03*
X460530D03*
X457330D03*
X454130D03*
X464413Y433598D03*
X460413D03*
X456413D03*
X452413D03*
X448413D03*
X465402Y54197D03*
X469402D03*
X473402D03*
X477402D03*
X481402D03*
X480413Y433598D03*
X476413D03*
X472413D03*
X468413D03*
X485402Y54197D03*
X489402D03*
X493402D03*
X497402D03*
X496413Y433598D03*
X492413D03*
X488413D03*
X484413D03*
X501402Y54197D03*
X505402D03*
X509402D03*
X513402D03*
X516413Y433598D03*
X512413D03*
X508413D03*
X504413D03*
X500413D03*
X517402Y54197D03*
X521402D03*
X525402D03*
X529402D03*
X533402D03*
X533000Y95000D03*
Y99500D03*
X528500Y299000D03*
X532413Y433598D03*
X528413D03*
X524413D03*
X520413D03*
X537402Y54197D03*
X541402D03*
X545402D03*
X549402D03*
X548413Y433598D03*
X544413D03*
X540413D03*
X536413D03*
X553402Y54197D03*
X557402D03*
X561402D03*
X565402D03*
X566600Y212900D03*
X552000Y367597D03*
Y371141D03*
X555200Y367597D03*
Y371141D03*
X552000Y374684D03*
Y378227D03*
X555200D03*
Y374684D03*
X568413Y433598D03*
X564413D03*
X560413D03*
X556413D03*
X552413D03*
X569402Y54197D03*
X573402D03*
X577402D03*
X581402D03*
X585402D03*
X584413Y433598D03*
X580413D03*
X576413D03*
X572413D03*
X589402Y54197D03*
X593402D03*
X597402D03*
X601402D03*
X600413Y433598D03*
X596413D03*
X592413D03*
X588413D03*
X605402Y54197D03*
X609402D03*
X613402D03*
X617402D03*
X621402D03*
X619961Y230874D03*
Y221274D03*
Y224474D03*
Y227674D03*
X620413Y433598D03*
X616413D03*
X612413D03*
X608413D03*
X604413D03*
X625402Y54197D03*
X629402D03*
X625800Y215874D03*
X636413Y433598D03*
X632413D03*
X628413D03*
X624413D03*
X649402Y54197D03*
X653402D03*
X656039Y57205D03*
Y61205D03*
Y65205D03*
Y69205D03*
Y73205D03*
Y77205D03*
Y81205D03*
Y85205D03*
Y89205D03*
Y93205D03*
Y97205D03*
Y101205D03*
Y105205D03*
Y109205D03*
Y113205D03*
Y117205D03*
Y121205D03*
Y125205D03*
Y129205D03*
Y145205D03*
Y133205D03*
Y137205D03*
Y141205D03*
Y149205D03*
Y153205D03*
Y157205D03*
Y161205D03*
Y165205D03*
Y169205D03*
Y173205D03*
Y177205D03*
Y181205D03*
Y235585D03*
Y311909D03*
Y315909D03*
Y319909D03*
Y323909D03*
Y327909D03*
Y331909D03*
Y335909D03*
Y339909D03*
Y343909D03*
Y347909D03*
Y351909D03*
Y355909D03*
Y359909D03*
Y363909D03*
Y367909D03*
Y371909D03*
Y375909D03*
Y379909D03*
Y383909D03*
Y387909D03*
Y391909D03*
Y395909D03*
Y399909D03*
Y403909D03*
Y407909D03*
Y411909D03*
Y415909D03*
Y419909D03*
Y423909D03*
Y427909D03*
Y431909D03*
X652413Y433598D03*
X648413D03*
X644413D03*
X640413D03*
G54D20*
X36950Y302840D03*
Y295160D03*
Y297720D03*
Y300280D03*
X55050Y295160D03*
Y302840D03*
Y300280D03*
Y297720D03*
G54D11*
X6039Y61260D03*
Y81260D03*
Y118346D03*
Y138346D03*
Y175433D03*
Y195433D03*
Y232520D03*
Y252520D03*
X26039Y61260D03*
Y81260D03*
Y118346D03*
Y138346D03*
Y175433D03*
Y195433D03*
Y232520D03*
Y252520D03*
G54D30*
X246559Y228700D03*
X241441Y219300D03*
Y228700D03*
X244000Y219300D03*
X246559D03*
G54D21*
X95000Y84500D03*
X110500Y414500D03*
X578000Y116500D03*
G54D12*
X11264Y152264D03*
X17500Y91000D03*
X12500Y96000D03*
X19100Y148798D03*
X23600D03*
X28100D03*
X17000Y204500D03*
X12500Y209500D03*
X11963Y266437D03*
X28700Y262508D03*
X19900Y283000D03*
X16000Y302500D03*
Y297500D03*
Y307500D03*
X24100Y310900D03*
X18000Y314500D03*
X11976Y323524D03*
X45500Y126000D03*
X41500Y127500D03*
X41409Y132591D03*
X45500Y161000D03*
X41600Y148798D03*
X32600Y148700D03*
X37100Y148798D03*
X45000Y213000D03*
X42000Y236800D03*
X37400Y282900D03*
X43000Y314500D03*
X33000D03*
X39500Y309000D03*
X34500D03*
X59600Y60200D03*
X51772Y73600D03*
X47600Y68900D03*
X60100Y73000D03*
X47000Y100000D03*
X61400Y104900D03*
X50500Y104800D03*
X62500Y100500D03*
Y117000D03*
X48390Y128312D03*
X51772Y130500D03*
X46500Y133000D03*
X53900Y157000D03*
X60600Y161200D03*
X60500Y152000D03*
X51400Y161600D03*
X51772Y187987D03*
X58000Y213500D03*
X54000D03*
X63000Y206000D03*
Y210500D03*
Y215000D03*
X57500Y218500D03*
X51452Y219900D03*
X51772Y245074D03*
X54590Y266870D03*
X48232Y264530D03*
X48500Y271500D03*
X52500Y278000D03*
X62000Y307000D03*
X61489Y332329D03*
X62000Y323500D03*
X63500Y359600D03*
X62500Y365000D03*
Y369000D03*
Y382000D03*
X60300Y401100D03*
Y413100D03*
X67700Y65000D03*
X66400Y77400D03*
X66000Y91100D03*
X76400Y87200D03*
X76321Y78300D03*
X78500Y82250D03*
X69500Y100000D03*
X67500Y114500D03*
X68000Y119000D03*
X73500D03*
X69500Y130000D03*
X74000D03*
X75000Y141700D03*
X64445Y168945D03*
X69000Y187500D03*
Y193000D03*
X69023Y198524D03*
X74593Y202207D03*
X71400Y221700D03*
X67500Y222900D03*
X67400Y227100D03*
X71400Y232900D03*
X71500Y247800D03*
X68000Y235500D03*
X67700Y240200D03*
X80148Y253648D03*
X64248Y258000D03*
X64500Y296750D03*
X78000Y291500D03*
X66000Y318500D03*
X72000Y335000D03*
X66000Y323500D03*
X79500Y341790D03*
X72000Y346300D03*
X73000Y365000D03*
X69500D03*
X66000D03*
X66500Y382000D03*
X70500D03*
X80700Y399200D03*
Y404200D03*
X71300D03*
Y399200D03*
X76000D03*
Y404200D03*
X71300Y394200D03*
X76000D03*
X80700D03*
X64300Y407600D03*
Y395600D03*
X66000Y419000D03*
X80700Y409200D03*
X76000D03*
X71300D03*
X88900Y67000D03*
X86000Y63100D03*
X83300Y87100D03*
X82100Y79300D03*
X96500Y98000D03*
X92250Y97750D03*
X94500Y105000D03*
X89000Y110500D03*
X90500Y105000D03*
X87000Y130000D03*
Y120000D03*
X86600Y141300D03*
X90500Y144500D03*
X96500Y140000D03*
X91500D03*
X88400Y154900D03*
X93900Y155200D03*
X94500Y163000D03*
X88250Y177250D03*
X83500Y178000D03*
X97500Y172000D03*
X95500Y192000D03*
X83500Y193000D03*
Y188500D03*
X85750Y202750D03*
X97500Y214000D03*
X93032Y246477D03*
X96000Y241000D03*
X85700Y236500D03*
X87200Y258300D03*
X98500Y256661D03*
X86900Y267200D03*
X95900Y278900D03*
X94500Y312500D03*
X95000Y321500D03*
X95593Y333347D03*
X82500Y339000D03*
X97500Y341000D03*
X95000Y344500D03*
X82800Y364600D03*
X94500Y373000D03*
Y369000D03*
Y364500D03*
X90500D03*
X86500D03*
X91500Y359500D03*
X83500Y360000D03*
X82800Y384600D03*
X94000Y384500D03*
X90500D03*
X86500D03*
X94500Y376500D03*
X85400Y404200D03*
Y399200D03*
Y394200D03*
X92800Y408100D03*
X96800Y402100D03*
Y396100D03*
X92800D03*
X94000Y420000D03*
X83000Y417000D03*
X85400Y409200D03*
X96800Y414100D03*
X111330Y59810D03*
X103800Y76240D03*
X99000Y175500D03*
Y188500D03*
Y197500D03*
Y206500D03*
Y201500D03*
Y260025D03*
X98800Y272400D03*
X112500Y290000D03*
X102500D03*
Y302000D03*
X104500Y305500D03*
X115253Y306247D03*
X99000Y350000D03*
X101500Y341000D03*
X104019Y347425D03*
X113000Y344500D03*
X103000Y364000D03*
X106500D03*
X110000D03*
X115500Y389000D03*
X104500Y377000D03*
X102500Y420000D03*
X119500Y57694D03*
X125000Y76500D03*
X127500Y290500D03*
X117500Y290000D03*
X125095Y306095D03*
X129000Y321500D03*
X123500Y347500D03*
X130000Y349664D03*
X120000Y364500D03*
X129000Y365000D03*
Y370500D03*
X120000Y368000D03*
Y371500D03*
X132000Y379000D03*
X118500D03*
X132000Y375500D03*
X127000Y397061D03*
X117000Y397000D03*
X121169Y396892D03*
X145000Y296500D03*
X141000Y298500D03*
X140100Y306900D03*
X135000Y312000D03*
X149500Y311034D03*
X140700Y320000D03*
X142130Y325630D03*
X146000Y334000D03*
X141916Y333916D03*
X140900Y355400D03*
X142000Y350000D03*
X148000Y370000D03*
X137000Y364000D03*
X140123Y391604D03*
X135500Y383000D03*
Y390500D03*
X141000Y379500D03*
X148500Y380000D03*
X145000Y378000D03*
X140100Y395600D03*
X135500Y396000D03*
X140000Y401000D03*
X135100Y412600D03*
X143500Y418000D03*
X153270Y58400D03*
X151200Y75191D03*
X160500Y75500D03*
Y71500D03*
X165000Y294000D03*
X166150Y304050D03*
X156000Y316500D03*
X166700Y338800D03*
X151000Y324200D03*
X156000Y325000D03*
Y329000D03*
X159100Y350400D03*
Y354600D03*
X166700Y343800D03*
X151500Y370000D03*
Y358000D03*
X159100Y382600D03*
X163600Y378600D03*
X158500Y405200D03*
X160582Y410000D03*
X160550Y413400D03*
X168500Y294000D03*
X169850Y298950D03*
X182600Y289500D03*
X178600Y378600D03*
Y374600D03*
X175100Y387100D03*
X174600Y401600D03*
Y406100D03*
X175000Y394500D03*
X176000Y416000D03*
X188900Y54960D03*
X192160Y77840D03*
X190000Y301500D03*
Y305500D03*
X189500Y319000D03*
X189000Y326000D03*
X195900Y332500D03*
X191500Y413000D03*
X213500Y54000D03*
X208160Y73990D03*
X215000Y69000D03*
X220000D03*
X204770Y67780D03*
X207800Y83010D03*
X219200Y338800D03*
X219000Y348800D03*
X218000Y381100D03*
X219000Y392500D03*
X215500D03*
X216500Y396000D03*
X220000D03*
X217600Y415100D03*
X223500Y58250D03*
X231000Y68000D03*
Y71500D03*
X228500Y75500D03*
Y79000D03*
X226500Y334000D03*
X222500Y324500D03*
X238000Y345000D03*
X225500Y347500D03*
X230000D03*
X221500Y378500D03*
X226000D03*
X221500Y415000D03*
X225600Y415100D03*
X229500Y415000D03*
X254000Y213500D03*
X241441Y215000D03*
X241900Y238800D03*
X249000Y290300D03*
X247000Y344500D03*
X251000D03*
X255000D03*
X272330Y54871D03*
X259500Y54700D03*
Y70100D03*
X271000Y184500D03*
X269000Y215000D03*
X259000Y223000D03*
Y344500D03*
X282200Y179121D03*
X275260Y223000D03*
X280500Y224300D03*
X288000Y293000D03*
X288500Y317000D03*
X303500Y69400D03*
X296400Y70200D03*
X307500Y160500D03*
X303500Y164000D03*
X298284Y175184D03*
X298500Y184500D03*
X300995Y187611D03*
X297772Y188694D03*
X292000Y294720D03*
X299500Y295500D03*
X301000Y312000D03*
Y317000D03*
X309000Y164500D03*
X311000Y193500D03*
X308967Y204000D03*
X312000Y234400D03*
X324000Y220750D03*
X312500Y225400D03*
X311900Y243400D03*
X311600Y252400D03*
X312000Y269000D03*
Y256500D03*
Y264500D03*
X314500Y276500D03*
X312000Y295500D03*
X317500D03*
X321000D03*
X324500D03*
X310500Y321000D03*
X312500Y307500D03*
X310600Y326000D03*
X321899Y343000D03*
X325000Y363000D03*
X320000Y398500D03*
X324800Y415200D03*
X321300Y416700D03*
X324800Y410700D03*
X336000Y61060D03*
X340500Y63500D03*
Y87000D03*
X338000Y102500D03*
X341500Y233500D03*
X327923Y221577D03*
X335153Y217875D03*
X340953Y237000D03*
X333500Y258900D03*
X339500Y282000D03*
X330500Y291500D03*
X341000Y304000D03*
X332500Y306500D03*
X328000D03*
X338000Y315000D03*
X341400Y323500D03*
X326000Y374000D03*
X340500Y361300D03*
X332500D03*
X325300Y387200D03*
X331500Y376000D03*
X338500D03*
X342000D03*
X339200Y380300D03*
X339300Y384000D03*
Y387700D03*
X340500Y391600D03*
X325300Y396200D03*
Y391700D03*
X336300Y415200D03*
Y419200D03*
X340800Y415200D03*
X349500Y61000D03*
X354500Y60920D03*
X345500Y87000D03*
X354000Y82500D03*
Y128000D03*
X351000Y130500D03*
X353500D03*
X356000D03*
X347500Y141500D03*
X350000D03*
X352500D03*
X355000D03*
X357000Y154200D03*
X353482Y154157D03*
X350085Y154300D03*
X350100Y169400D03*
X352600D03*
X357600D03*
X355100D03*
X347300Y179000D03*
X346500Y174000D03*
X344500Y181500D03*
X351200Y196600D03*
X349128Y186628D03*
X350500Y229500D03*
X355500Y218000D03*
Y220500D03*
Y225500D03*
Y223000D03*
X351000Y233243D03*
X355000Y242500D03*
X354975Y247900D03*
X351000Y237000D03*
X343500Y258900D03*
X352500Y260000D03*
X348500D03*
X357680Y271780D03*
X349000Y303000D03*
Y295500D03*
X355500Y306500D03*
X355000Y337000D03*
X348418Y361300D03*
X344500D03*
X360000Y402400D03*
X359800Y397700D03*
X348279Y405678D03*
X353000Y416500D03*
X350000Y419500D03*
X349500Y415000D03*
X346000Y416000D03*
X376838Y100230D03*
X369310Y109500D03*
X369172Y102828D03*
X367000Y126000D03*
X374300Y129000D03*
X371800D03*
X362000Y123500D03*
Y128000D03*
X374300Y132000D03*
X371800D03*
X376500Y141000D03*
X374000D03*
X360500Y154500D03*
X374900Y154228D03*
X371400Y154300D03*
X367900Y154228D03*
X363600Y176600D03*
X367600Y169300D03*
X364700Y169400D03*
X367400Y174400D03*
X373649Y185735D03*
X369560Y213000D03*
X372060D03*
X367000D03*
X364500D03*
X372500Y232000D03*
X377500Y218500D03*
Y221000D03*
Y223500D03*
X360500Y243000D03*
X367000Y241243D03*
X373500Y247000D03*
X369500Y267500D03*
X375800Y255200D03*
X365000Y268000D03*
X362300Y286100D03*
X365800D03*
X370000Y276000D03*
X374500D03*
X374800Y291100D03*
X370300D03*
X361500Y296100D03*
X365800Y291100D03*
X362100Y291000D03*
X361400Y301500D03*
Y305800D03*
Y309900D03*
X365500Y305900D03*
X375500Y309200D03*
X371000Y326000D03*
X370000Y337000D03*
X366000Y350850D03*
X360700Y406200D03*
X363100Y418300D03*
X360311Y409880D03*
X363100Y422800D03*
X364500Y413500D03*
X384000Y102980D03*
Y109500D03*
X379000Y141000D03*
X378400Y154300D03*
X379800Y177100D03*
X380000Y204500D03*
X379500Y237500D03*
X391900Y246800D03*
X386000D03*
X380100D03*
X386000Y259250D03*
X378000Y273500D03*
Y281000D03*
X382200D03*
X388650Y292650D03*
X378000Y293200D03*
X383000D03*
X393300Y312500D03*
X383000Y341500D03*
X384300Y368700D03*
X383900Y372600D03*
X381000Y365000D03*
X386500D03*
X389500Y370000D03*
X383900Y384600D03*
X379500Y417500D03*
X407000Y120000D03*
X399500D03*
X399000Y221407D03*
Y225000D03*
X407500D03*
X397800Y246800D03*
X403700D03*
X409300D03*
X397800Y259300D03*
X403700D03*
X400000Y265500D03*
X399800Y278400D03*
X409100Y281300D03*
X409300Y286300D03*
X402000Y303000D03*
X409200Y291700D03*
X407500Y300500D03*
X402500Y308000D03*
X397500Y312900D03*
X407500Y305000D03*
X397300Y320700D03*
X408500Y316500D03*
X398000Y336500D03*
Y352000D03*
X411840Y353620D03*
X410000Y358543D03*
X409650Y403950D03*
X412350Y401250D03*
Y397150D03*
X409650Y394450D03*
X422000Y77500D03*
X423000Y72950D03*
X417500Y75000D03*
X413500Y88500D03*
X423000Y100500D03*
X427800Y100300D03*
X429400Y107500D03*
X420900Y246800D03*
X415000D03*
X420900Y259000D03*
X413000Y300500D03*
X417500Y337000D03*
Y352000D03*
X428500Y346000D03*
X413500Y373500D03*
X419000D03*
X425000Y381000D03*
X420500D03*
X419150Y394450D03*
X416450Y401250D03*
Y397150D03*
X419150Y403950D03*
X423500Y415500D03*
X434500Y77000D03*
X433500Y100500D03*
X444200D03*
X431000Y116500D03*
X444000Y226000D03*
X436500Y233000D03*
X444000Y250000D03*
X439500D03*
X435000Y250500D03*
X439500Y266500D03*
X444000Y263000D03*
X440000Y278500D03*
X434600Y278300D03*
X435500Y274500D03*
X445600Y278300D03*
X438150Y283800D03*
X433050Y291400D03*
X439000Y302000D03*
X434500D03*
X433000Y314320D03*
X435143Y306643D03*
X434000Y328000D03*
X447200Y347500D03*
X433000Y353500D03*
X446000Y374500D03*
X438400Y382400D03*
X431000Y416000D03*
X460000Y76000D03*
X448430Y89540D03*
X463500Y86500D03*
Y92000D03*
X450000Y108200D03*
X454600Y108500D03*
X448500Y100500D03*
X462500Y117000D03*
X462000Y224500D03*
X461000Y234500D03*
X457500Y227500D03*
Y223500D03*
X462000Y250000D03*
X457500D03*
X448500D03*
X457500Y237400D03*
X453000Y250000D03*
X457000Y258500D03*
X459500Y262000D03*
X461500Y268409D03*
X460000Y284500D03*
Y289500D03*
X460800Y294200D03*
X461000Y302500D03*
X464500Y298500D03*
X456500Y305500D03*
X461500Y311000D03*
X451000Y306500D03*
X459500Y322000D03*
X459000Y326000D03*
X450900Y330900D03*
X450500Y368500D03*
X453500Y381500D03*
X454000Y393500D03*
Y397000D03*
X450000Y407000D03*
X481000Y70700D03*
X478000Y78000D03*
X465500Y78500D03*
X479867Y138867D03*
X481500Y182016D03*
X477500Y170500D03*
X478000Y198000D03*
X471000Y239000D03*
X477000D03*
X477500Y259000D03*
X468500Y264500D03*
Y270000D03*
X471000Y347000D03*
X481000Y341000D03*
X471400Y363300D03*
X470500Y391000D03*
X493700Y79161D03*
X496000Y85000D03*
X489400Y126300D03*
X493300Y121500D03*
X496000Y163000D03*
Y167500D03*
Y179258D03*
X485033Y174934D03*
X496500Y192500D03*
Y197500D03*
X497500Y214000D03*
X496000Y205500D03*
X485000Y202739D03*
X490500Y216750D03*
X497500Y226000D03*
X497100Y244700D03*
X497200Y240600D03*
X492300Y240800D03*
X492500Y272200D03*
X491800Y277700D03*
X495000Y346000D03*
X488500D03*
X504000Y64500D03*
X508500D03*
X513200Y66000D03*
X508000Y105500D03*
Y110500D03*
Y115500D03*
X503860Y124150D03*
X503900Y128690D03*
X503950Y143000D03*
Y133500D03*
X514500Y151000D03*
Y148000D03*
Y154000D03*
Y157000D03*
X501500Y192500D03*
X507000D03*
Y188500D03*
X515500Y201000D03*
X513000Y210500D03*
X511500Y206500D03*
X513500Y215500D03*
X509000D03*
X512100Y249500D03*
X507100Y240700D03*
X512100D03*
Y244700D03*
X502200Y240700D03*
X512100Y262500D03*
X512300Y254400D03*
X512200Y258700D03*
X512650Y268150D03*
X511900Y276200D03*
X508950Y273250D03*
X506100Y280600D03*
X509000Y340500D03*
X504500D03*
X514000Y374000D03*
X505000Y379500D03*
X504500Y376000D03*
X507500Y394500D03*
X526500Y67500D03*
X533000Y87000D03*
Y82000D03*
X524900Y99000D03*
X522500Y114500D03*
X533500Y124500D03*
X534000Y160500D03*
X517000Y212500D03*
X529800Y223000D03*
X528710Y227500D03*
X534000Y231500D03*
X525400Y247000D03*
X522000D03*
X530350Y257480D03*
X524300Y261700D03*
X523900Y257100D03*
X532500Y272500D03*
X523600Y281100D03*
X531000Y285500D03*
X526000Y295500D03*
X532900Y318900D03*
X527600D03*
X519000Y307500D03*
X532400Y340600D03*
Y345600D03*
X527100Y340600D03*
Y345600D03*
X517500Y374000D03*
X532200Y377700D03*
X523700Y384100D03*
X528200Y377700D03*
X523700D03*
X518000Y382500D03*
X532100Y399000D03*
X527500Y393100D03*
X525176Y411925D03*
X522100Y416500D03*
X551500Y59597D03*
X543957Y60543D03*
X537000Y69000D03*
X549000Y78223D03*
X544300Y87100D03*
X549400Y81600D03*
X534500Y130000D03*
Y136500D03*
X534600Y148300D03*
Y152000D03*
X544000Y159000D03*
X543520Y174970D03*
X542270Y169900D03*
X539770Y174900D03*
Y169900D03*
Y172400D03*
X542270D03*
X542500Y189500D03*
X538500D03*
X540900Y201500D03*
X543500Y205000D03*
X536900Y201500D03*
X545800Y216500D03*
X537500Y232000D03*
X546500Y240500D03*
X549000Y267500D03*
X551700Y256300D03*
X541000Y281500D03*
X541346Y303507D03*
X542000Y296450D03*
X537500Y304000D03*
X538600Y318900D03*
X538100Y340600D03*
Y345600D03*
X539000Y370000D03*
X539300Y365100D03*
X539000Y360000D03*
X543000Y370000D03*
X543300Y365100D03*
X538500Y407875D03*
X543000Y396700D03*
X562500Y74600D03*
X560650Y70450D03*
X559941Y62120D03*
X563341Y62102D03*
X564350Y65350D03*
X559000Y85000D03*
X560200Y81500D03*
X559000Y88800D03*
X565933Y102000D03*
X562533Y102001D03*
X553000Y108500D03*
X568700Y204300D03*
X564700Y204400D03*
X554600Y202400D03*
X566950Y220000D03*
X553800Y240200D03*
X560000Y240000D03*
X565400Y244700D03*
X562000Y254870D03*
X554400Y267500D03*
X556700Y320300D03*
X562500Y336100D03*
X562000Y331600D03*
X564500Y379000D03*
X560200Y386500D03*
X567500Y403000D03*
X555000Y402000D03*
X580500Y65800D03*
X580643Y60900D03*
X585900Y79600D03*
X576459Y161971D03*
X575072Y165500D03*
X580500Y194500D03*
X583000Y192000D03*
X573200Y204300D03*
X586500Y230000D03*
X571000Y217900D03*
X585000Y226500D03*
X578900Y236600D03*
X581500Y267000D03*
X581400Y292250D03*
X583000Y297000D03*
X580300Y356700D03*
X576300Y371200D03*
X580200Y361700D03*
X580100Y366700D03*
X580300Y380700D03*
Y375700D03*
Y385700D03*
Y390700D03*
X576900Y403100D03*
X584000Y421900D03*
X599000Y92500D03*
X588000Y96500D03*
X592000Y127063D03*
X599500Y116500D03*
X597703Y187000D03*
X594003D03*
X601550Y208450D03*
X596450Y210350D03*
X590650Y245680D03*
X604000Y398000D03*
X597500Y421900D03*
X616500Y194874D03*
X610500Y190500D03*
X614100Y224100D03*
X610500Y227000D03*
X614100Y236400D03*
X618650Y249300D03*
X614500Y398000D03*
X637900Y116900D03*
X622000Y127063D03*
Y136000D03*
X633500Y196874D03*
X628500Y189500D03*
X636000Y216142D03*
X627500Y205374D03*
X626989Y237989D03*
X633500Y301500D03*
X647000Y108000D03*
Y113500D03*
G54D22*
X109000Y351200D03*
Y345800D03*
X132000Y354800D03*
Y360200D03*
X226000Y67700D03*
Y62300D03*
X284500Y216800D03*
Y222200D03*
X318500Y285300D03*
Y290700D03*
X377000Y86300D03*
Y91700D03*
X427000Y77800D03*
Y83200D03*
X570000Y231800D03*
Y237200D03*
G54D40*
X574250Y263750D03*
X573750Y292250D03*
G54D31*
X255906Y309646D03*
Y412008D03*
X494094Y309646D03*
Y412008D03*
G54D13*
X9000Y279000D03*
Y286000D03*
X12500Y91000D03*
Y101000D03*
Y106000D03*
X13620Y148720D03*
X13000Y157000D03*
X12500Y162000D03*
Y204500D03*
Y214500D03*
Y219500D03*
X19000Y262500D03*
X24200Y262508D03*
X12500Y261500D03*
X15000Y279000D03*
X28700Y274300D03*
X13000Y273327D03*
X28500Y302000D03*
X28000Y296500D03*
X13000Y318700D03*
X28000Y327000D03*
X44500Y73500D03*
X46000Y82000D03*
X45500Y104390D03*
Y182500D03*
X46000Y219500D03*
X40500Y262000D03*
X33200Y262508D03*
X43000Y255500D03*
X29000Y291500D03*
X44500Y309000D03*
X35500Y327000D03*
X55500Y59000D03*
X50500Y60228D03*
X63500Y84500D03*
X57000Y83500D03*
X51500D03*
X59000Y96500D03*
X51765Y96600D03*
X57500Y101500D03*
X56500Y113000D03*
X53740Y126000D03*
X55922Y140543D03*
X47500Y140500D03*
X54130Y152500D03*
X60600Y157000D03*
X48957Y153619D03*
X54500Y171000D03*
X62000Y199500D03*
X53500Y183500D03*
X48000Y200500D03*
X53000D03*
X49600Y213455D03*
X57500Y226500D03*
X53200Y240187D03*
X48500Y252500D03*
X55200Y253500D03*
X52800Y272000D03*
X63600Y291500D03*
X57500Y289000D03*
X61800Y302500D03*
X55000Y336000D03*
Y355400D03*
X62500Y373000D03*
Y378000D03*
X60300Y407100D03*
Y395100D03*
X75500Y62000D03*
X64400Y70000D03*
X71500Y77000D03*
X73500Y112500D03*
X67000Y109000D03*
X79000Y100500D03*
X74000D03*
X64500Y129500D03*
X76100Y154400D03*
X75950Y164200D03*
X79500Y234500D03*
X64700Y251700D03*
X79600Y248900D03*
X72400Y264600D03*
X69500Y257800D03*
X77964Y260100D03*
X75800Y274300D03*
X72000Y271400D03*
X79500Y308500D03*
X79000Y315500D03*
X71000Y330500D03*
X78000D03*
X78635Y324492D03*
X79500Y348500D03*
X64300Y401600D03*
X80500Y420500D03*
X70500Y419000D03*
X75580Y419004D03*
X64300Y413600D03*
X84200Y75000D03*
X93500Y110500D03*
X84000Y100500D03*
X93500Y125000D03*
X87000Y125500D03*
X93500Y130000D03*
X95500Y145500D03*
X95200Y151000D03*
X88500Y149000D03*
X98500Y159000D03*
X91000Y181500D03*
X98500Y165500D03*
X92000Y173000D03*
X83500D03*
X90500Y188500D03*
X94500Y197000D03*
X90500Y193500D03*
X84500Y218000D03*
X95700Y227500D03*
X98500Y218500D03*
X82500Y230500D03*
X84600Y248900D03*
X96500Y235500D03*
X89600Y248900D03*
X98700Y268300D03*
X83200Y260300D03*
X82500Y273200D03*
X87100Y271300D03*
X94500Y299000D03*
X88500Y303000D03*
X95000Y291500D03*
X87500Y295500D03*
X85800Y287452D03*
X82951Y327940D03*
X95100Y351900D03*
X83000Y352500D03*
Y344500D03*
X94500Y380500D03*
X97800Y391800D03*
X96800Y408100D03*
X92800Y402100D03*
Y414100D03*
X112800Y66600D03*
X112880Y73020D03*
X100500Y284730D03*
X112500Y302000D03*
X107500D03*
X105410Y318500D03*
X103000Y351500D03*
X114000Y352000D03*
X99500Y370000D03*
X126000Y67000D03*
Y62000D03*
Y72000D03*
Y318000D03*
X129500Y328000D03*
X119000Y352000D03*
X124500D03*
X148500Y62500D03*
X139500D03*
X150860Y67400D03*
X142070Y77900D03*
X142000Y69535D03*
X145000Y359000D03*
X148500Y376000D03*
X138500Y387500D03*
X135200Y408400D03*
X156800Y301100D03*
X156600Y295000D03*
X153500Y310500D03*
X156000Y320500D03*
X153900Y382200D03*
X163300Y382900D03*
X157900Y387400D03*
X151100Y386300D03*
X167800Y392700D03*
X152100Y399300D03*
X151530Y406300D03*
X153150Y394590D03*
X160600Y417400D03*
X152200Y416300D03*
X151700Y411300D03*
X183170Y56390D03*
X180620Y77890D03*
X180390Y70720D03*
X173170Y70840D03*
X180910Y63390D03*
X179500Y294600D03*
X176500Y290000D03*
X178000Y309500D03*
X173800Y324100D03*
X175100Y382600D03*
X177000Y398000D03*
X174600Y410600D03*
X201370Y43000D03*
X192400Y45786D03*
X198000Y49500D03*
X195000Y54550D03*
X203000Y75000D03*
X196497Y76502D03*
X201700Y327900D03*
X208295Y52500D03*
X207880Y78740D03*
X214810Y78810D03*
X218500Y301700D03*
X213500D03*
X208500D03*
X205000Y337500D03*
Y348800D03*
Y353800D03*
X215000Y343800D03*
X229582Y48918D03*
X222000Y330000D03*
X228500Y382500D03*
X225000Y396000D03*
X243500Y48650D03*
X252700Y44000D03*
X249499Y204000D03*
X255400Y290100D03*
X266500Y206500D03*
X264500Y214000D03*
X287500Y203500D03*
X307300Y61300D03*
X306500Y169500D03*
X295000Y213000D03*
X292500Y222850D03*
X297000Y310500D03*
X293700Y317300D03*
X297700Y335100D03*
X312500Y160500D03*
X320500Y170000D03*
X312000Y217000D03*
X324000Y227500D03*
X311900Y229900D03*
X324000Y236000D03*
X323500Y263000D03*
X318000Y268500D03*
X324300Y254700D03*
X324000Y301000D03*
X323000Y401500D03*
X321300Y423600D03*
X338500Y213500D03*
X332550Y213550D03*
X327500Y232000D03*
X332600Y246600D03*
X328500Y238645D03*
X327800Y246800D03*
X330500Y265000D03*
X337500D03*
X328500Y258900D03*
X338500Y259000D03*
X334350Y282000D03*
X332000Y301500D03*
X336500Y295000D03*
X336525Y320500D03*
Y325500D03*
X341500Y338500D03*
Y328500D03*
Y333500D03*
X336525Y330500D03*
X337000Y344000D03*
X336500Y361300D03*
X330000Y411300D03*
X336300Y423200D03*
X349000Y82500D03*
X344000Y103000D03*
X358400Y182700D03*
X344000Y212000D03*
X345930Y217000D03*
X342900Y246800D03*
X358000Y261500D03*
X344500Y265000D03*
X357000Y295500D03*
X356000Y302300D03*
X344000Y295000D03*
X346000Y306500D03*
X351000Y308000D03*
X358250Y340050D03*
X347700Y381600D03*
X347000Y391200D03*
X347600Y398800D03*
X343700Y409900D03*
X348863Y410500D03*
X370500Y84000D03*
X374600Y178200D03*
X375000Y210000D03*
X367000Y232000D03*
X377500Y226500D03*
X365500Y246500D03*
X376500Y269000D03*
X365500Y279500D03*
X370000Y332500D03*
X361124Y349876D03*
X369000Y413500D03*
X374500Y418500D03*
X379500Y72500D03*
X381700Y92400D03*
X382286Y86214D03*
X382000Y142000D03*
X380000Y210000D03*
X387193Y209933D03*
X384091Y200091D03*
X394000Y223500D03*
X383000Y232500D03*
X390000D03*
X389400Y281100D03*
X394800Y281300D03*
X391600Y304800D03*
X379300Y305000D03*
X383000Y328500D03*
Y333500D03*
Y323500D03*
X390000Y338500D03*
X392500Y329100D03*
Y323900D03*
X383000Y346600D03*
X395000Y370000D03*
Y360000D03*
Y382000D03*
X388500Y391000D03*
X393500D03*
X379500Y381000D03*
Y375800D03*
X396400Y100500D03*
X410816Y190248D03*
X399005Y209933D03*
X406879D03*
X396981Y304482D03*
X408500Y321998D03*
Y311000D03*
X408000Y327000D03*
X410000Y338000D03*
X406610Y353410D03*
X409000Y371339D03*
X405463Y383000D03*
X410463D03*
X398500Y391000D03*
X420500Y82000D03*
X425000Y87700D03*
X429000Y123500D03*
X422000D03*
X418500Y117000D03*
X415000Y123500D03*
X426564Y143005D03*
Y186311D03*
X425400Y229600D03*
X420500Y229500D03*
X414900Y229800D03*
X423000Y235400D03*
X416100D03*
X429000Y274000D03*
X424900Y284300D03*
X423900Y278500D03*
X424900Y292900D03*
X429442Y310075D03*
X422500Y354500D03*
X421360Y359970D03*
X420500Y366000D03*
X415463Y383000D03*
X441400Y78100D03*
X438374Y202059D03*
X442311Y209933D03*
X436749Y225000D03*
X443500Y231500D03*
X436500Y237500D03*
X443500Y236500D03*
X447000Y283000D03*
X446000Y294000D03*
X441500Y297500D03*
X447000Y321998D03*
X440000Y332500D03*
X433500Y366500D03*
X433382Y360466D03*
X438500Y364500D03*
X430000Y386500D03*
Y381000D03*
X444000Y406500D03*
X431900Y392200D03*
X431169Y401169D03*
X431000Y406500D03*
X444000Y411500D03*
X431000D03*
X458500Y86500D03*
X461996Y162690D03*
X454122Y217807D03*
X449000Y232500D03*
Y227500D03*
X461000Y230000D03*
X448500Y237500D03*
X454000Y312500D03*
X448500Y311500D03*
X450000Y416500D03*
Y411500D03*
X479500Y92500D03*
X482000Y83500D03*
X475500Y82500D03*
X470500D03*
X466500Y110400D03*
X471200Y115700D03*
X481600Y125800D03*
X476800Y120700D03*
X473807Y154816D03*
X465933Y162690D03*
X473807Y150879D03*
X475000Y163000D03*
X481000Y172500D03*
X479246Y178464D03*
X481500Y193000D03*
X482000Y212500D03*
X480288Y203788D03*
X465933Y202059D03*
X471000Y259200D03*
X467000Y355500D03*
X478500Y346000D03*
X470462Y369462D03*
X470500Y395000D03*
X482800Y110300D03*
X483000Y133000D03*
X490970Y133500D03*
Y138500D03*
X485000Y154000D03*
X497500Y148500D03*
X491000Y154000D03*
X491500Y148500D03*
X497000Y154000D03*
X484000Y166000D03*
X497000Y175000D03*
X498060Y185500D03*
X483871Y198241D03*
X484000Y185500D03*
X492500Y226000D03*
X483100Y272800D03*
X497000Y341000D03*
X483501Y346000D03*
X488500Y359000D03*
X493500D03*
X503005Y99494D03*
X514500Y144000D03*
X503000Y155000D03*
X503500Y149000D03*
X501000Y263500D03*
X500500Y271100D03*
X500000Y278799D03*
X503000Y354600D03*
X503500Y394500D03*
X521500Y60000D03*
X529500Y60500D03*
X519500Y75500D03*
Y81500D03*
X520000Y87000D03*
X533200Y220000D03*
X534500Y253600D03*
X522400Y270700D03*
X522600Y276200D03*
X527500Y389100D03*
X530000Y406500D03*
X527500Y397100D03*
X532300Y425700D03*
X549000Y63500D03*
X549500Y69400D03*
X544500Y79500D03*
X536500Y84500D03*
Y79000D03*
X541000Y96000D03*
X547211Y209800D03*
X541000Y216400D03*
X540600Y234600D03*
X548300Y222600D03*
X548158Y228033D03*
X545250Y256300D03*
X539977Y275124D03*
X540318Y270436D03*
X537500Y296607D03*
X539500Y292000D03*
X543000Y360000D03*
X548557Y387700D03*
X540600Y386300D03*
X537200Y396300D03*
X550643Y400900D03*
X548829Y416329D03*
X548500Y411000D03*
X538558Y413779D03*
X550369Y427558D03*
X538558D03*
X568600Y76000D03*
X558000Y161500D03*
X558900Y202500D03*
X553122Y227979D03*
X559500Y228000D03*
X566700Y227500D03*
X564350Y238443D03*
X561700Y320300D03*
X562500Y326100D03*
X566000Y347000D03*
X563700Y352400D03*
X568000Y356700D03*
X560000Y342100D03*
X568100Y366400D03*
Y361700D03*
X568326Y371200D03*
X563800Y390700D03*
X567500Y386500D03*
X568600Y376000D03*
Y380700D03*
X555569Y388051D03*
X560000Y401000D03*
X564400Y396700D03*
X561731Y408500D03*
X567126Y417500D03*
X555315D03*
X562180Y413779D03*
Y427558D03*
X572500Y60301D03*
X572870Y67570D03*
X580000Y104800D03*
X576500Y98000D03*
X586500Y107000D03*
Y112500D03*
X576500Y219700D03*
X577100Y227900D03*
X569943Y223300D03*
X576000Y246500D03*
X581400Y262100D03*
Y272100D03*
Y282100D03*
X581500Y302100D03*
X576200Y342500D03*
X571800Y396500D03*
X578937Y417500D03*
X572500Y413500D03*
X585500Y409500D03*
X573991Y427558D03*
X600850Y112350D03*
X592000Y136000D03*
Y141000D03*
Y146000D03*
Y163000D03*
Y151500D03*
Y157063D03*
Y173000D03*
Y178000D03*
Y168000D03*
X587000Y184000D03*
X597000Y199900D03*
X587500Y190000D03*
X602500Y183000D03*
X591902Y200300D03*
X601902Y200100D03*
X594153Y220500D03*
X601953Y218853D03*
X595500Y239000D03*
X589953Y236600D03*
X604000Y254500D03*
X591000Y261500D03*
Y271500D03*
Y278500D03*
X590500Y301500D03*
X591000Y291500D03*
X602500Y404000D03*
X591000D03*
X602559Y417500D03*
X590748Y418725D03*
X597613Y413779D03*
Y427558D03*
X606902Y186000D03*
Y200400D03*
X609500Y254500D03*
X614500Y403500D03*
X614370Y417500D03*
X609424Y413779D03*
Y427558D03*
X633500Y108000D03*
Y102000D03*
Y96500D03*
X622000Y141500D03*
Y146500D03*
Y162000D03*
Y151600D03*
Y157000D03*
Y181500D03*
Y175500D03*
X622035Y167063D03*
X623000Y205375D03*
X633500Y205906D03*
X633000Y267000D03*
Y286500D03*
G54D14*
X29528Y36811D03*
Y373031D03*
X640039Y65354D03*
Y417835D03*
G54D41*
X588779Y334449D03*
Y350984D03*
Y367519D03*
X605315Y334449D03*
Y350984D03*
G54D23*
X126067Y104043D03*
Y184043D03*
Y264043D03*
X253967Y93443D03*
X265967D03*
X277867D03*
X286067Y104043D03*
Y264043D03*
G54D32*
X269000Y219350D03*
X265260D03*
Y230650D03*
X272740Y219350D03*
Y230650D03*
G54D42*
X605315Y367519D03*
G54D33*
X285000Y227700D03*
Y234300D03*
X296000Y284700D03*
X303500D03*
X296000Y291300D03*
X303500D03*
X311000Y284700D03*
Y291300D03*
X318500Y375700D03*
Y382300D03*
X346000Y131200D03*
Y137800D03*
X378500Y130200D03*
Y136800D03*
X366200Y295200D03*
Y301800D03*
X540000Y178700D03*
Y185300D03*
G54D24*
X143567Y106043D03*
X146067Y268043D03*
X268567Y112143D03*
Y255943D03*
G54D15*
X19878Y36811D03*
X22704Y29987D03*
Y43635D03*
X22834Y340080D03*
X26378D03*
X28150Y343150D03*
X24606D03*
X19878Y373031D03*
X22704Y366207D03*
Y379855D03*
X29528Y27161D03*
X36352Y29987D03*
X39178Y36811D03*
X36352Y43635D03*
X29528Y46461D03*
X29922Y340080D03*
X33466D03*
X37010D03*
X40554D03*
X44098D03*
X45870Y343150D03*
X42326D03*
X38782D03*
X35238D03*
X31694D03*
X29528Y363381D03*
X36352Y366207D03*
X39178Y373031D03*
X36352Y379855D03*
X29528Y382681D03*
X633215Y58530D03*
Y72178D03*
X630389Y65354D03*
X633215Y424659D03*
X630389Y417835D03*
X633215Y411011D03*
X640039Y55704D03*
X646863Y58530D03*
X649689Y65354D03*
X646863Y72178D03*
X640039Y75004D03*
Y408185D03*
X646863Y411011D03*
X649689Y417835D03*
X646863Y424659D03*
X640039Y427485D03*
G54D34*
X305350Y214300D03*
X305850Y231500D03*
X297150Y235200D03*
Y227800D03*
X296650Y218000D03*
X305350Y221700D03*
G54D43*
X634055Y334449D03*
Y367519D03*
G54D25*
X147200Y409000D03*
X141800D03*
X351600Y388700D03*
X357000D03*
X361800Y139500D03*
X367200D03*
G54D16*
X16039Y71260D03*
Y128346D03*
Y185433D03*
Y242520D03*
G54D44*
X651582Y197244D03*
Y224804D03*
G54D17*
X24100Y297500D03*
X19900D03*
Y302500D03*
X24100D03*
Y292500D03*
X19900D03*
Y287500D03*
X24100D03*
Y307500D03*
X19900D03*
X63500Y61500D03*
X67700D03*
X80900Y66500D03*
X71700Y154400D03*
X67500D03*
X80800Y163900D03*
Y159400D03*
X80400Y150000D03*
X71600Y149500D03*
X67400D03*
X80800Y154900D03*
X71800Y159900D03*
X67600D03*
X80800Y168400D03*
X69900Y291500D03*
X74100D03*
X74600Y320000D03*
X70400D03*
Y315500D03*
X74600D03*
Y324500D03*
X70400D03*
X88900Y71000D03*
X84700D03*
X85100Y66500D03*
X85000Y163900D03*
Y159400D03*
X84600Y150000D03*
X85000Y154900D03*
Y168400D03*
X91100Y345500D03*
X86900D03*
X91100Y350000D03*
X86900D03*
X91100Y341000D03*
X86900D03*
X103800Y71800D03*
X108000D03*
X115400Y347500D03*
X130900Y75300D03*
X117370Y70860D03*
X121570D03*
X121580Y65870D03*
X117380D03*
X130850Y65800D03*
X130870Y70800D03*
X133400Y350000D03*
X119600Y347500D03*
X135100Y75300D03*
X135050Y65800D03*
X135070Y70800D03*
X147900Y300000D03*
X138100Y328000D03*
X133900D03*
X138100Y323500D03*
X133900D03*
X137600Y350000D03*
X147700Y390100D03*
X143500D03*
X146700Y385100D03*
X142500D03*
X147700Y403600D03*
X143500D03*
Y394600D03*
X147700D03*
X143500Y399100D03*
X147700D03*
X143500Y414200D03*
X147700D03*
X152100Y300000D03*
X154000Y377600D03*
X158200D03*
X166600Y388500D03*
X162400D03*
X176600Y391000D03*
X172400D03*
X210400Y336000D03*
X214600D03*
X210400Y355000D03*
X214600D03*
X210400Y350000D03*
X214600D03*
X241900Y235500D03*
X246100D03*
X255100Y237500D03*
X250900D03*
X259900D03*
X264100D03*
X283850Y194500D03*
X279650D03*
X304100Y205000D03*
X299900D03*
X304100Y200500D03*
X299900D03*
X306800Y321000D03*
X302600D03*
Y330500D03*
X306800D03*
X302600Y335000D03*
X306800D03*
Y326000D03*
X302600D03*
X324400Y407000D03*
X341900Y225500D03*
X332900D03*
X337100D03*
Y221000D03*
X332900D03*
X341900D03*
X329800Y320500D03*
X325600D03*
X329800Y329500D03*
X325600D03*
X329800Y334000D03*
X325600D03*
X329800Y338500D03*
X325600D03*
X329800Y325000D03*
X325600D03*
X329800Y347500D03*
X325600D03*
X329800Y343000D03*
X325600D03*
X328600Y407000D03*
X334400Y409500D03*
X338600D03*
X357500Y193149D03*
X353300D03*
X357500Y188649D03*
X353300D03*
X346100Y225500D03*
Y221000D03*
X350600Y337000D03*
X346400D03*
X350600Y332500D03*
X346400D03*
X350600Y328000D03*
X346400D03*
X350600Y323500D03*
X346400D03*
X350600Y341500D03*
X346400D03*
X352200Y394200D03*
X356400D03*
Y403200D03*
X352200D03*
Y407700D03*
X356400D03*
Y398700D03*
X352200D03*
X359400Y419700D03*
X355200D03*
X353900Y413000D03*
X358100D03*
X374600Y172000D03*
X370400D03*
X365100Y217000D03*
X360900D03*
X374400Y323500D03*
Y328000D03*
Y332500D03*
Y337000D03*
Y341500D03*
X387629Y129361D03*
X391829D03*
X384430Y174500D03*
X388630D03*
X383500Y309200D03*
X379300D03*
X393300D03*
X389100D03*
X378600Y323500D03*
Y328000D03*
Y332500D03*
Y337000D03*
Y341500D03*
X383900Y375800D03*
X388100D03*
X383900Y381000D03*
X388100D03*
X409800Y175000D03*
X402400Y221500D03*
X406600D03*
X401500Y323900D03*
X397300D03*
X401500Y329100D03*
X397300D03*
X426900Y73000D03*
X414000Y175000D03*
X419900D03*
X424100D03*
X426600Y406500D03*
X422400D03*
X426600Y411500D03*
X422400D03*
X431100Y73000D03*
X432300Y174100D03*
X436500D03*
X446511Y175500D03*
X442311D03*
X445485Y222000D03*
X436600Y297500D03*
X432400D03*
X435400Y386500D03*
X439600D03*
Y396500D03*
X435400D03*
Y406500D03*
X439600D03*
X435400Y411500D03*
X439600D03*
X455511Y175500D03*
X451311D03*
X463900D03*
X449685Y222000D03*
X456600Y284500D03*
X452400D03*
Y279500D03*
X456600D03*
Y289500D03*
X452400D03*
Y294500D03*
X456600D03*
X461400Y389500D03*
Y394000D03*
X473600Y91500D03*
X469400D03*
X473600Y96500D03*
X469400D03*
X468100Y175500D03*
X473600Y355100D03*
X477800D03*
X465600Y389500D03*
Y394000D03*
X488400Y163000D03*
X492600D03*
Y167500D03*
X488400D03*
X492600Y176500D03*
X488400D03*
Y181000D03*
X492600D03*
X488400Y197500D03*
X492600D03*
X488400Y185500D03*
X492600D03*
Y202500D03*
X488400D03*
X498900Y345500D03*
X503100D03*
X544600Y69000D03*
X540400D03*
Y64000D03*
X544600D03*
X543100Y227500D03*
X538900D03*
X550400Y264000D03*
Y259500D03*
X550200Y272100D03*
X550400Y277000D03*
Y281500D03*
X550200Y292250D03*
X550400Y302000D03*
X549600Y287000D03*
X545400D03*
X550400Y306500D03*
X563100Y198000D03*
X558900D03*
X554600Y264000D03*
Y259500D03*
X554400Y272100D03*
X554600Y277000D03*
Y281500D03*
X554400Y292250D03*
X554600Y302000D03*
Y306500D03*
X552900Y407000D03*
X557100D03*
Y411500D03*
X552900D03*
X576200Y390700D03*
X572000D03*
X576200Y385700D03*
X572000D03*
X576900Y407500D03*
X581100D03*
Y412000D03*
X576900D03*
X599400Y261500D03*
X603600D03*
X599400Y279000D03*
X603600D03*
X637900Y96500D03*
Y102000D03*
Y108000D03*
X642100Y96500D03*
Y102000D03*
Y108000D03*
G54D35*
X393098Y152847D03*
X389160Y148910D03*
X393098D03*
Y164658D03*
Y176470D03*
Y172532D03*
Y184343D03*
Y200091D03*
X393097Y204028D03*
X393098Y207964D03*
Y211902D03*
X389160Y215839D03*
X393098D03*
X397035Y144973D03*
X404910Y141036D03*
Y137098D03*
X400973Y144972D03*
X397036Y152847D03*
X400973Y160720D03*
Y164658D03*
X397035Y148911D03*
X397036Y164658D03*
X400973Y148910D03*
X408847Y160721D03*
X404910Y164659D03*
Y160721D03*
X408847Y156784D03*
X400973Y156785D03*
Y152847D03*
X404909Y148910D03*
X408847D03*
X400972Y180406D03*
X404910D03*
X404909Y168595D03*
X408847D03*
X404910Y196155D03*
Y192217D03*
X397035D03*
X400973D03*
X408846Y196154D03*
X397036Y184343D03*
Y200091D03*
X397035Y204028D03*
X420658Y144973D03*
Y141035D03*
Y160720D03*
Y164658D03*
X412783Y148910D03*
X416721D03*
X412783Y152847D03*
X416721D03*
X420658Y148909D03*
Y152847D03*
X424595Y164659D03*
Y160721D03*
X416721Y164658D03*
X424596Y156784D03*
X420658D03*
X416721Y156783D03*
Y160721D03*
X412784Y164657D03*
X412785Y160721D03*
Y156784D03*
X420657Y180406D03*
X424595D03*
X416721Y168596D03*
X420657Y168595D03*
X424595D03*
X412784D03*
X420658Y188281D03*
Y184343D03*
X416721Y196154D03*
X412784D03*
X424595Y215840D03*
Y211902D03*
X416721Y200092D03*
X416722Y204028D03*
X412784D03*
X440343Y137099D03*
Y133161D03*
X444280Y141035D03*
Y144973D03*
X436406D03*
X430900Y144531D03*
X440343Y156783D03*
Y160721D03*
X444280Y164658D03*
Y160722D03*
Y156784D03*
X440343Y164657D03*
X436406Y164659D03*
Y160721D03*
Y148911D03*
Y152846D03*
Y156784D03*
X430900Y148469D03*
X444280Y168595D03*
X440343D03*
X440344Y180406D03*
X436406D03*
X444280Y180405D03*
X440342Y192217D03*
X444280D03*
X431006Y193718D03*
Y189780D03*
X444280Y184343D03*
X440343Y215839D03*
Y219777D03*
X463965Y129224D03*
X460027D03*
X452154Y141035D03*
Y137097D03*
X456090Y141035D03*
X460028D03*
X452155Y144973D03*
X448217D03*
X460028Y156785D03*
Y152847D03*
X452154Y164657D03*
X448217Y156783D03*
Y160721D03*
X448218Y164658D03*
X463964Y156784D03*
X448218Y168595D03*
X452154D03*
X460027D03*
X463965D03*
Y180406D03*
X452154D03*
X448217Y180405D03*
X463966Y196154D03*
X460028D03*
X463966Y192217D03*
X460028D03*
X463965Y188281D03*
Y184343D03*
X448216Y196154D03*
Y192216D03*
X452154Y184344D03*
X448217Y184343D03*
X456090D03*
X460028D03*
X460029Y188280D03*
X456091D03*
X448216Y207965D03*
X452154D03*
X476666Y138867D03*
Y142805D03*
X467902Y156784D03*
X467903Y180406D03*
X467901Y168595D03*
X471839D03*
X467902Y188281D03*
Y184343D03*
Y215840D03*
Y211902D03*
X475777Y200091D03*
X471839D03*
Y215840D03*
Y211902D03*
X471840Y207965D03*
X467902D03*
G54D26*
X183661Y13781D03*
X187598D03*
X199409D03*
X195472D03*
X191535D03*
X215157D03*
X211220D03*
X219094D03*
X207283D03*
X203346D03*
X234842D03*
X230905D03*
X238779D03*
X246653D03*
X250590D03*
X254527D03*
X242716D03*
X258464D03*
X266338D03*
X270275D03*
X262401D03*
X282086D03*
X286023D03*
X289960D03*
X278149D03*
X274212D03*
X297834D03*
X301771D03*
X305708D03*
X293897D03*
X309645D03*
G54D18*
X24807Y335985D03*
Y347245D03*
X43705Y331655D03*
Y351576D03*
G54D36*
X398250Y232500D03*
X408750D03*
G54D45*
X640952Y201181D03*
Y220867D03*
G54D27*
X179724Y15731D03*
G54D46*
G01X136000Y-65500D02*
Y-158000D01*
X506000D01*
Y-65500D01*
X136000D01*
G01X316000D02*
Y-158000D01*
G54D28*
X174850Y338800D03*
Y353800D03*
Y348800D03*
Y343800D03*
X196950Y338800D03*
Y343800D03*
Y348800D03*
Y353800D03*
G54D19*
X33500Y282900D03*
X29000D03*
X33500Y287100D03*
X29000D03*
X57700Y65500D03*
Y69700D03*
X53000D03*
Y65500D03*
X53500Y88400D03*
Y92600D03*
X53000Y144400D03*
Y148600D03*
Y204900D03*
Y209100D03*
Y258400D03*
Y262600D03*
X79900Y71100D03*
Y75300D03*
X72100Y81700D03*
Y85900D03*
X74300Y95300D03*
Y91100D03*
X78800Y95300D03*
Y91100D03*
X69800D03*
Y95300D03*
X76000Y240200D03*
Y244400D03*
X80500Y240200D03*
Y244400D03*
X71500D03*
Y240200D03*
X66000Y301400D03*
Y305600D03*
X70000Y338400D03*
Y342600D03*
X86000Y83300D03*
Y79100D03*
X87800Y91100D03*
Y95300D03*
X83300Y91100D03*
Y95300D03*
X89600Y244400D03*
Y240200D03*
X85000Y244400D03*
Y240200D03*
X90800Y278900D03*
Y283100D03*
X85800D03*
Y278900D03*
X95000Y356400D03*
X88200Y355300D03*
X95000Y360600D03*
X88200Y359500D03*
X103500Y309400D03*
Y313600D03*
X113000Y356400D03*
X99500D03*
X104000D03*
X108500D03*
X113000Y360600D03*
X105500Y368900D03*
Y373100D03*
X99500Y360600D03*
X104000D03*
X108500D03*
X128000Y309400D03*
Y313600D03*
X126500Y356400D03*
X117500D03*
X122000D03*
X126500Y360600D03*
X117500D03*
X122000D03*
X137500Y355900D03*
Y360100D03*
X163000Y350400D03*
Y354600D03*
X180000Y406600D03*
Y402400D03*
X186460Y60220D03*
Y64420D03*
X188500Y298100D03*
Y293900D03*
X215500Y65600D03*
Y61400D03*
X220000Y65600D03*
Y61400D03*
X217300Y293100D03*
Y297300D03*
X212800Y293100D03*
Y297300D03*
X208300Y293100D03*
Y297300D03*
X210500Y340900D03*
Y345100D03*
X234310Y58390D03*
Y62590D03*
X239311Y58400D03*
X246122D03*
X251122D03*
X239311Y62600D03*
X246122D03*
X251122D03*
X254000Y230600D03*
Y226400D03*
Y217400D03*
Y221600D03*
X265807Y58400D03*
X270807D03*
X265807Y62600D03*
X270807D03*
X259000Y226400D03*
Y230600D03*
X280055Y58400D03*
X285055D03*
X280055Y62600D03*
X285055D03*
X279500Y188000D03*
Y183800D03*
X279000Y216400D03*
Y229600D03*
Y233800D03*
Y220600D03*
X290000Y284400D03*
X285500D03*
X290000Y288600D03*
X285500D03*
X297303Y58400D03*
X302303D03*
X297303Y62600D03*
X302303D03*
X291000Y229900D03*
Y234100D03*
X324500Y285900D03*
Y290100D03*
X318500Y387900D03*
Y392100D03*
X333500Y251100D03*
Y255300D03*
X335000Y286400D03*
X339500D03*
X335000Y290600D03*
X339500D03*
X352000Y133400D03*
Y137600D03*
X350500Y178900D03*
Y183100D03*
X347000Y233400D03*
Y237600D03*
X344000Y286400D03*
X348500D03*
X344000Y290600D03*
X348500D03*
X377000Y76900D03*
Y81100D03*
X391900Y251000D03*
X386000D03*
X380100D03*
X391900Y255200D03*
X386000D03*
X380100D03*
X403700Y251000D03*
X397800D03*
X409300D03*
X403700Y255200D03*
X397800D03*
X409300D03*
X398000Y347100D03*
Y342900D03*
X427500Y91900D03*
Y96100D03*
X420900Y251000D03*
X415000D03*
X420900Y255200D03*
X415000D03*
X417000Y347100D03*
Y342900D03*
X424000Y398300D03*
Y394100D03*
X432000Y91900D03*
Y96100D03*
X441500Y107900D03*
Y112100D03*
X437000Y107900D03*
Y112100D03*
X430500Y164900D03*
Y159100D03*
Y154900D03*
Y169100D03*
X430600Y179500D03*
Y183700D03*
X430000Y198700D03*
Y202900D03*
X435000Y246100D03*
Y241900D03*
X444000Y246100D03*
Y241900D03*
X439500D03*
Y246100D03*
X453000Y113900D03*
Y118100D03*
X458500Y113900D03*
Y118100D03*
X462000Y241900D03*
Y246100D03*
X457500D03*
Y241900D03*
X448500Y246100D03*
Y241900D03*
X453000D03*
Y246100D03*
X478000Y182111D03*
Y186311D03*
X496100Y268600D03*
Y272800D03*
X488500Y354600D03*
Y350400D03*
X498500Y354600D03*
Y350400D03*
X493500Y354600D03*
Y350400D03*
X508500Y385400D03*
Y389600D03*
X503500Y385400D03*
Y389600D03*
X527800Y265300D03*
Y261100D03*
X527300Y420101D03*
Y415901D03*
X532300D03*
Y420101D03*
X539000Y160400D03*
Y164600D03*
X551000Y202400D03*
Y206600D03*
Y212900D03*
Y217100D03*
Y232400D03*
X546500D03*
X551000Y236600D03*
X546500D03*
X545250Y267950D03*
Y263750D03*
X545200Y277100D03*
Y281300D03*
Y292250D03*
Y296450D03*
Y301900D03*
Y306100D03*
X543500Y416600D03*
Y412400D03*
Y421900D03*
Y426100D03*
X555700Y70500D03*
Y74700D03*
X555500Y65000D03*
Y60800D03*
X560000Y232400D03*
X555500D03*
X560000Y236600D03*
X555500D03*
X567500Y408400D03*
X567000Y421900D03*
Y426100D03*
X555500Y421900D03*
Y426100D03*
X567500Y412600D03*
X582500Y75400D03*
X577500D03*
X577200Y65800D03*
Y70000D03*
X582500Y79600D03*
X577500D03*
X575400Y232400D03*
Y236600D03*
X579000Y421900D03*
Y426100D03*
X598000Y141900D03*
Y146100D03*
Y153900D03*
Y158100D03*
Y163400D03*
Y167600D03*
Y173900D03*
Y178100D03*
X591902Y195065D03*
Y190865D03*
X596902D03*
Y195065D03*
X601902Y190865D03*
Y195065D03*
X602500Y408900D03*
X591000D03*
X602700Y421900D03*
Y426100D03*
X602500Y413100D03*
X591000D03*
X617000Y147600D03*
Y143400D03*
Y157600D03*
Y153400D03*
Y163400D03*
Y167600D03*
X615500Y176900D03*
Y181100D03*
X606902Y190865D03*
Y195065D03*
X621000Y196774D03*
Y200974D03*
X614000Y421900D03*
Y426100D03*
X614500Y409400D03*
Y413600D03*
X625500Y196774D03*
X630000D03*
X625500Y200974D03*
X630000D03*
G54D37*
X531600Y351999D03*
Y369401D03*
G54D47*
G01X329433Y-125500D02*
Y-133000D01*
X333167D01*
G01X340480D02*
Y-128000D01*
G01Y-128875D02*
X340107Y-128375D01*
X339547Y-128125D01*
X338893Y-128000D01*
X338240Y-128250D01*
X337680Y-128750D01*
X337307Y-129500D01*
X337120Y-130500D01*
X337307Y-131500D01*
X337680Y-132250D01*
X338240Y-132750D01*
X338893Y-133000D01*
X339547Y-132875D01*
X340107Y-132500D01*
X340480Y-132000D01*
G01X344340Y-135250D02*
X344900Y-135500D01*
X345647Y-135250D01*
X346113Y-134750D01*
X346487Y-134125D01*
X347047Y-132125D01*
X348260Y-128000D01*
G01X345273D02*
X347047Y-132125D01*
G01X352400Y-129625D02*
X355387D01*
X355107Y-128750D01*
X354640Y-128250D01*
X353987Y-128000D01*
X353333Y-128125D01*
X352773Y-128500D01*
X352400Y-129375D01*
X352213Y-130125D01*
Y-130875D01*
X352400Y-131625D01*
X352867Y-132375D01*
X353427Y-132875D01*
X354080Y-133000D01*
X354733Y-132750D01*
X355387Y-132000D01*
G01X359993Y-133000D02*
Y-128000D01*
G01Y-129000D02*
X360460Y-128500D01*
X360927Y-128125D01*
X361580Y-128000D01*
X362047Y-128125D01*
X362607Y-128500D01*
G01X368800Y-133250D02*
X368613Y-133125D01*
Y-132875D01*
X368800Y-132750D01*
X368987Y-132875D01*
Y-133125D01*
X368800Y-133250D01*
G01Y-129875D02*
X368613Y-129750D01*
Y-129500D01*
X368800Y-129375D01*
X368987Y-129500D01*
Y-129750D01*
X368800Y-129875D01*
G01X336747Y-120500D02*
Y-113000D01*
X338613D01*
X339360Y-113375D01*
X339920Y-113875D01*
X340387Y-114625D01*
X340760Y-115500D01*
X340853Y-116750D01*
X340760Y-118000D01*
X340387Y-118875D01*
X339920Y-119625D01*
X339360Y-120125D01*
X338613Y-120500D01*
X336747D01*
G01X347980D02*
Y-115500D01*
G01Y-116375D02*
X347607Y-115875D01*
X347047Y-115625D01*
X346393Y-115500D01*
X345740Y-115750D01*
X345180Y-116250D01*
X344807Y-117000D01*
X344620Y-118000D01*
X344807Y-119000D01*
X345180Y-119750D01*
X345740Y-120250D01*
X346393Y-120500D01*
X347047Y-120375D01*
X347607Y-120000D01*
X347980Y-119500D01*
G01X353800Y-113000D02*
Y-120500D01*
G01X352493Y-115500D02*
X355107D01*
G01X359900Y-117125D02*
X362887D01*
X362607Y-116250D01*
X362140Y-115750D01*
X361487Y-115500D01*
X360833Y-115625D01*
X360273Y-116000D01*
X359900Y-116875D01*
X359713Y-117625D01*
Y-118375D01*
X359900Y-119125D01*
X360367Y-119875D01*
X360927Y-120375D01*
X361580Y-120500D01*
X362233Y-120250D01*
X362887Y-119500D01*
G01X368800Y-120750D02*
X368613Y-120625D01*
Y-120375D01*
X368800Y-120250D01*
X368987Y-120375D01*
Y-120625D01*
X368800Y-120750D01*
G01Y-117375D02*
X368613Y-117250D01*
Y-117000D01*
X368800Y-116875D01*
X368987Y-117000D01*
Y-117250D01*
X368800Y-117375D01*
G01X382027Y-114250D02*
X382587Y-113500D01*
X383240Y-113125D01*
X383987Y-113000D01*
X384920Y-113250D01*
X385573Y-113875D01*
X385760Y-114625D01*
X385667Y-115375D01*
X385293Y-116000D01*
X383427Y-117250D01*
X382587Y-118125D01*
X382027Y-119375D01*
X381840Y-120500D01*
X385760D01*
G01X391300Y-113000D02*
X390553Y-113250D01*
X389993Y-113875D01*
X389620Y-114625D01*
X389340Y-115625D01*
X389247Y-116750D01*
X389340Y-117875D01*
X389620Y-118875D01*
X389993Y-119625D01*
X390553Y-120250D01*
X391300Y-120500D01*
X392047Y-120250D01*
X392607Y-119625D01*
X392980Y-118875D01*
X393260Y-117875D01*
X393353Y-116750D01*
X393260Y-115625D01*
X392980Y-114625D01*
X392607Y-113875D01*
X392047Y-113250D01*
X391300Y-113000D01*
G01X397027Y-114250D02*
X397587Y-113500D01*
X398240Y-113125D01*
X398987Y-113000D01*
X399920Y-113250D01*
X400573Y-113875D01*
X400760Y-114625D01*
X400667Y-115375D01*
X400293Y-116000D01*
X398427Y-117250D01*
X397587Y-118125D01*
X397027Y-119375D01*
X396840Y-120500D01*
X400760D01*
G01X404527Y-114250D02*
X405087Y-113500D01*
X405740Y-113125D01*
X406487Y-113000D01*
X407420Y-113250D01*
X408073Y-113875D01*
X408260Y-114625D01*
X408167Y-115375D01*
X407793Y-116000D01*
X405927Y-117250D01*
X405087Y-118125D01*
X404527Y-119375D01*
X404340Y-120500D01*
X408260D01*
G01X412587Y-118000D02*
X415013D01*
G01X421300Y-113000D02*
X420553Y-113250D01*
X419993Y-113875D01*
X419620Y-114625D01*
X419340Y-115625D01*
X419247Y-116750D01*
X419340Y-117875D01*
X419620Y-118875D01*
X419993Y-119625D01*
X420553Y-120250D01*
X421300Y-120500D01*
X422047Y-120250D01*
X422607Y-119625D01*
X422980Y-118875D01*
X423260Y-117875D01*
X423353Y-116750D01*
X423260Y-115625D01*
X422980Y-114625D01*
X422607Y-113875D01*
X422047Y-113250D01*
X421300Y-113000D01*
G01X427027Y-114250D02*
X427587Y-113500D01*
X428240Y-113125D01*
X428987Y-113000D01*
X429920Y-113250D01*
X430573Y-113875D01*
X430760Y-114625D01*
X430667Y-115375D01*
X430293Y-116000D01*
X428427Y-117250D01*
X427587Y-118125D01*
X427027Y-119375D01*
X426840Y-120500D01*
X430760D01*
G01X435087Y-118000D02*
X437513D01*
G01X442027Y-114250D02*
X442587Y-113500D01*
X443240Y-113125D01*
X443987Y-113000D01*
X444920Y-113250D01*
X445573Y-113875D01*
X445760Y-114625D01*
X445667Y-115375D01*
X445293Y-116000D01*
X443427Y-117250D01*
X442587Y-118125D01*
X442027Y-119375D01*
X441840Y-120500D01*
X445760D01*
G01X449247Y-119375D02*
X449807Y-120000D01*
X450460Y-120375D01*
X451300Y-120500D01*
X452140Y-120250D01*
X452793Y-119750D01*
X453260Y-118875D01*
X453353Y-117875D01*
X453167Y-116875D01*
X452700Y-116250D01*
X452047Y-115750D01*
X451393Y-115625D01*
X450740Y-115750D01*
X449900Y-116250D01*
X450180Y-113000D01*
X452700D01*
G01X336933Y-108000D02*
Y-100500D01*
X339267D01*
X340013Y-100875D01*
X340480Y-101375D01*
X340667Y-102375D01*
X340480Y-103375D01*
X339920Y-104000D01*
X339267Y-104375D01*
X336933D01*
G01X339267D02*
X340667Y-108000D01*
G01X344900Y-104625D02*
X347887D01*
X347607Y-103750D01*
X347140Y-103250D01*
X346487Y-103000D01*
X345833Y-103125D01*
X345273Y-103500D01*
X344900Y-104375D01*
X344713Y-105125D01*
Y-105875D01*
X344900Y-106625D01*
X345367Y-107375D01*
X345927Y-107875D01*
X346580Y-108000D01*
X347233Y-107750D01*
X347887Y-107000D01*
G01X352120Y-103000D02*
X353800Y-108000D01*
X355480Y-103000D01*
G01X368800Y-108250D02*
X368613Y-108125D01*
Y-107875D01*
X368800Y-107750D01*
X368987Y-107875D01*
Y-108125D01*
X368800Y-108250D01*
G01Y-104875D02*
X368613Y-104750D01*
Y-104500D01*
X368800Y-104375D01*
X368987Y-104500D01*
Y-104750D01*
X368800Y-104875D01*
G01X383800Y-100500D02*
X383053Y-100750D01*
X382493Y-101375D01*
X382120Y-102125D01*
X381840Y-103125D01*
X381747Y-104250D01*
X381840Y-105375D01*
X382120Y-106375D01*
X382493Y-107125D01*
X383053Y-107750D01*
X383800Y-108000D01*
X384547Y-107750D01*
X385107Y-107125D01*
X385480Y-106375D01*
X385760Y-105375D01*
X385853Y-104250D01*
X385760Y-103125D01*
X385480Y-102125D01*
X385107Y-101375D01*
X384547Y-100750D01*
X383800Y-100500D01*
G01X391300Y-108000D02*
Y-100500D01*
X390180Y-102000D01*
G01Y-108000D02*
X392420D01*
G01X336933Y-95500D02*
Y-88000D01*
X339173D01*
X339920Y-88375D01*
X340480Y-89250D01*
X340667Y-90250D01*
X340480Y-91250D01*
X340013Y-92000D01*
X339173Y-92375D01*
X336933D01*
G01X344620Y-95750D02*
X347980Y-88000D01*
G01X351653Y-95500D02*
Y-88000D01*
X355947Y-95500D01*
Y-88000D01*
G01X368800Y-95750D02*
X368613Y-95625D01*
Y-95375D01*
X368800Y-95250D01*
X368987Y-95375D01*
Y-95625D01*
X368800Y-95750D01*
G01Y-92375D02*
X368613Y-92250D01*
Y-92000D01*
X368800Y-91875D01*
X368987Y-92000D01*
Y-92250D01*
X368800Y-92375D01*
G01X381933Y-95500D02*
Y-88000D01*
X384267D01*
X385013Y-88375D01*
X385480Y-88875D01*
X385667Y-89875D01*
X385480Y-90875D01*
X384920Y-91500D01*
X384267Y-91875D01*
X381933D01*
G01X384267D02*
X385667Y-95500D01*
G01X392420D02*
Y-88000D01*
X388967Y-93375D01*
X393633D01*
G01X398800Y-88000D02*
X398053Y-88250D01*
X397493Y-88875D01*
X397120Y-89625D01*
X396840Y-90625D01*
X396747Y-91750D01*
X396840Y-92875D01*
X397120Y-93875D01*
X397493Y-94625D01*
X398053Y-95250D01*
X398800Y-95500D01*
X399547Y-95250D01*
X400107Y-94625D01*
X400480Y-93875D01*
X400760Y-92875D01*
X400853Y-91750D01*
X400760Y-90625D01*
X400480Y-89625D01*
X400107Y-88875D01*
X399547Y-88250D01*
X398800Y-88000D01*
G01X406300D02*
X405553Y-88250D01*
X404993Y-88875D01*
X404620Y-89625D01*
X404340Y-90625D01*
X404247Y-91750D01*
X404340Y-92875D01*
X404620Y-93875D01*
X404993Y-94625D01*
X405553Y-95250D01*
X406300Y-95500D01*
X407047Y-95250D01*
X407607Y-94625D01*
X407980Y-93875D01*
X408260Y-92875D01*
X408353Y-91750D01*
X408260Y-90625D01*
X407980Y-89625D01*
X407607Y-88875D01*
X407047Y-88250D01*
X406300Y-88000D01*
G01X412027Y-92375D02*
X412680Y-91500D01*
X413240Y-91000D01*
X413987Y-90750D01*
X414640Y-91000D01*
X415107Y-91500D01*
X415480Y-92250D01*
X415573Y-93125D01*
X415480Y-93875D01*
X415107Y-94625D01*
X414547Y-95250D01*
X413893Y-95500D01*
X413147Y-95250D01*
X412493Y-94500D01*
X412120Y-93375D01*
X412027Y-92125D01*
X412213Y-90500D01*
X412493Y-89625D01*
X412960Y-88750D01*
X413613Y-88125D01*
X414267Y-88000D01*
X414920Y-88250D01*
X415387Y-88875D01*
G01X420087Y-93000D02*
X422513D01*
G01X429547Y-91500D02*
X429920Y-91125D01*
X430200Y-90500D01*
X430387Y-89625D01*
X430200Y-88875D01*
X429827Y-88375D01*
X429173Y-88000D01*
X426653D01*
Y-95500D01*
X429733D01*
X430387Y-95000D01*
X430760Y-94250D01*
X430947Y-93375D01*
X430760Y-92500D01*
X430200Y-91750D01*
X429547Y-91500D01*
X426653D01*
G01X436300Y-88000D02*
X435553Y-88250D01*
X434993Y-88875D01*
X434620Y-89625D01*
X434340Y-90625D01*
X434247Y-91750D01*
X434340Y-92875D01*
X434620Y-93875D01*
X434993Y-94625D01*
X435553Y-95250D01*
X436300Y-95500D01*
X437047Y-95250D01*
X437607Y-94625D01*
X437980Y-93875D01*
X438260Y-92875D01*
X438353Y-91750D01*
X438260Y-90625D01*
X437980Y-89625D01*
X437607Y-88875D01*
X437047Y-88250D01*
X436300Y-88000D01*
G01X443800D02*
X443053Y-88250D01*
X442493Y-88875D01*
X442120Y-89625D01*
X441840Y-90625D01*
X441747Y-91750D01*
X441840Y-92875D01*
X442120Y-93875D01*
X442493Y-94625D01*
X443053Y-95250D01*
X443800Y-95500D01*
X444547Y-95250D01*
X445107Y-94625D01*
X445480Y-93875D01*
X445760Y-92875D01*
X445853Y-91750D01*
X445760Y-90625D01*
X445480Y-89625D01*
X445107Y-88875D01*
X444547Y-88250D01*
X443800Y-88000D01*
G01X451300D02*
X450553Y-88250D01*
X449993Y-88875D01*
X449620Y-89625D01*
X449340Y-90625D01*
X449247Y-91750D01*
X449340Y-92875D01*
X449620Y-93875D01*
X449993Y-94625D01*
X450553Y-95250D01*
X451300Y-95500D01*
X452047Y-95250D01*
X452607Y-94625D01*
X452980Y-93875D01*
X453260Y-92875D01*
X453353Y-91750D01*
X453260Y-90625D01*
X452980Y-89625D01*
X452607Y-88875D01*
X452047Y-88250D01*
X451300Y-88000D01*
G01X458800Y-95500D02*
Y-88000D01*
X457680Y-89500D01*
G01Y-95500D02*
X459920D01*
G01X465087Y-93000D02*
X467513D01*
G01X473800Y-88000D02*
X473053Y-88250D01*
X472493Y-88875D01*
X472120Y-89625D01*
X471840Y-90625D01*
X471747Y-91750D01*
X471840Y-92875D01*
X472120Y-93875D01*
X472493Y-94625D01*
X473053Y-95250D01*
X473800Y-95500D01*
X474547Y-95250D01*
X475107Y-94625D01*
X475480Y-93875D01*
X475760Y-92875D01*
X475853Y-91750D01*
X475760Y-90625D01*
X475480Y-89625D01*
X475107Y-88875D01*
X474547Y-88250D01*
X473800Y-88000D01*
G01X479527Y-89250D02*
X480087Y-88500D01*
X480740Y-88125D01*
X481487Y-88000D01*
X482420Y-88250D01*
X483073Y-88875D01*
X483260Y-89625D01*
X483167Y-90375D01*
X482793Y-91000D01*
X480927Y-92250D01*
X480087Y-93125D01*
X479527Y-94375D01*
X479340Y-95500D01*
X483260D01*
G01X384628Y-132267D02*
X385375Y-132892D01*
X386215Y-133267D01*
X386961D01*
X387708Y-132892D01*
X388268Y-132267D01*
X388548Y-131392D01*
X388361Y-130517D01*
X387895Y-129767D01*
X387055Y-129267D01*
X385935Y-129017D01*
X385281Y-128517D01*
X385001Y-127642D01*
X385188Y-126767D01*
X385655Y-126142D01*
X386308Y-125767D01*
X386961D01*
X387615Y-126017D01*
X388175Y-126642D01*
G01X394088Y-133267D02*
X393341Y-133142D01*
X392688Y-132642D01*
X392128Y-131892D01*
X391755Y-131017D01*
X391568Y-130017D01*
Y-129017D01*
X391755Y-128017D01*
X392128Y-127142D01*
X392688Y-126392D01*
X393341Y-125892D01*
X394088Y-125767D01*
X394835Y-125892D01*
X395488Y-126392D01*
X396048Y-127142D01*
X396421Y-128017D01*
X396608Y-129017D01*
Y-130017D01*
X396421Y-131017D01*
X396048Y-131892D01*
X395488Y-132642D01*
X394835Y-133142D01*
X394088Y-133267D01*
G01X399721Y-125767D02*
Y-133267D01*
X403455D01*
G01X407035D02*
Y-125767D01*
X408901D01*
X409648Y-126142D01*
X410208Y-126642D01*
X410675Y-127392D01*
X411048Y-128267D01*
X411141Y-129517D01*
X411048Y-130767D01*
X410675Y-131642D01*
X410208Y-132392D01*
X409648Y-132892D01*
X408901Y-133267D01*
X407035D01*
G01X418455D02*
X414721D01*
Y-125767D01*
X418455D01*
G01X416961Y-129392D02*
X414721D01*
G01X422221Y-133267D02*
Y-125767D01*
X424555D01*
X425301Y-126142D01*
X425768Y-126642D01*
X425955Y-127642D01*
X425768Y-128642D01*
X425208Y-129267D01*
X424555Y-129642D01*
X422221D01*
G01X424555D02*
X425955Y-133267D01*
G01X429161D02*
Y-125767D01*
X431588Y-132017D01*
X434015Y-125767D01*
Y-133267D01*
G01X436755D02*
X439088Y-125767D01*
X441421Y-133267D01*
G01X440581Y-130642D02*
X437595D01*
G01X444628Y-132267D02*
X445375Y-132892D01*
X446215Y-133267D01*
X446961D01*
X447708Y-132892D01*
X448268Y-132267D01*
X448548Y-131392D01*
X448361Y-130517D01*
X447895Y-129767D01*
X447055Y-129267D01*
X445935Y-129017D01*
X445281Y-128517D01*
X445001Y-127642D01*
X445188Y-126767D01*
X445655Y-126142D01*
X446308Y-125767D01*
X446961D01*
X447615Y-126017D01*
X448175Y-126642D01*
G01X452035Y-133267D02*
Y-125767D01*
G01X455581D02*
X452035Y-130392D01*
G01X456141Y-133267D02*
X453621Y-128267D01*
G01X469835Y-129267D02*
X470208Y-128892D01*
X470488Y-128267D01*
X470675Y-127392D01*
X470488Y-126642D01*
X470115Y-126142D01*
X469461Y-125767D01*
X466941D01*
Y-133267D01*
X470021D01*
X470675Y-132767D01*
X471048Y-132017D01*
X471235Y-131142D01*
X471048Y-130267D01*
X470488Y-129517D01*
X469835Y-129267D01*
X466941D01*
G01X476588Y-133267D02*
X475841Y-133142D01*
X475188Y-132642D01*
X474628Y-131892D01*
X474255Y-131017D01*
X474068Y-130017D01*
Y-129017D01*
X474255Y-128017D01*
X474628Y-127142D01*
X475188Y-126392D01*
X475841Y-125892D01*
X476588Y-125767D01*
X477335Y-125892D01*
X477988Y-126392D01*
X478548Y-127142D01*
X478921Y-128017D01*
X479108Y-129017D01*
Y-130017D01*
X478921Y-131017D01*
X478548Y-131892D01*
X477988Y-132642D01*
X477335Y-133142D01*
X476588Y-133267D01*
G01X484088Y-125767D02*
Y-133267D01*
G01X481941Y-125767D02*
X486235D01*
G54D29*
X180700Y413000D03*
X187300D03*
X306800Y194500D03*
X300200D03*
X373200Y106000D03*
X367800Y223000D03*
X361200D03*
X379800Y106000D03*
X413400Y285500D03*
X420000D03*
X413400Y293600D03*
X420000D03*
X493300Y126300D03*
X499900D03*
X508000Y245400D03*
X501400D03*
X546100Y320600D03*
X546500Y336400D03*
Y328800D03*
Y344100D03*
X568700Y199000D03*
X552700Y320600D03*
X553100Y336400D03*
Y328800D03*
Y344100D03*
X575300Y199000D03*
G54D38*
X564500Y233457D03*
Y235543D03*
G54D48*
G01X658071Y284646D02*
G03X660039Y286614I0J1968D01*
G01Y433661D01*
G03X656102Y437598I-3937J0D01*
G01X3937D01*
G03X0Y433661I0J-3937D01*
G01Y21654D01*
G03X3937Y17717I3937J0D01*
G01X55118D01*
G03X59055Y21654I0J3937D01*
G01Y46260D01*
G02X62992Y50197I3937J0D01*
G01X127362D01*
G02X131299Y46260I0J-3937D01*
G01Y21654D01*
G03X135236Y17717I3937J0D01*
G01X158858D01*
G03X162795Y21654I0J3937D01*
G01Y43012D01*
G02X177165I7185J0D01*
G01Y1969D01*
X179134Y0D01*
X219291D01*
X221260Y1969D01*
Y29331D01*
G02X228740I3740J0D01*
G01Y1969D01*
X230709Y0D01*
X310236D01*
X312205Y1969D01*
Y46260D01*
G02X316142Y50197I3937J0D01*
G01X656102D01*
G03X660039Y54134I0J3937D01*
G01Y237500D01*
G03X658071Y239469I-1969J1D01*
G01X657211D01*
G02X655243Y241437I0J1968D01*
G01Y282677D01*
G02X657211Y284646I1968J0D01*
G01X658071D01*
G01X145964Y-110118D02*
G03I-634J0D01*
G01X149695D02*
G03I-1038J0D01*
G01X168013Y-137456D02*
G03I-634J0D01*
G01X155900Y-133655D02*
G03I-632J0D01*
G01X161735Y-128639D02*
G03I-1458J0D01*
G01X158530Y-131428D02*
G03I-1041J0D01*
G01X158461Y-119126D02*
G03I-1283J0D01*
G01X162690Y-117490D02*
G03I-1584J0D01*
G01X169809Y-121292D02*
G03I-2180J0D01*
G01X165531Y-125255D02*
G03I-1869J0D01*
G01X167813Y-115513D02*
G03I-1971J0D01*
G01X154775Y-120500D02*
G03I-892J0D01*
G01X162681Y-102774D02*
G03I-1584J0D01*
G01X158451Y-101149D02*
G03I-1283J0D01*
G01X159258Y-110118D02*
G03I-1868J0D01*
G01X169812Y-98951D02*
G03I-2180J0D01*
G01X167802Y-104739D02*
G03I-1971J0D01*
G01X165183Y-110118D02*
G03I-2180J0D01*
G01X171881D02*
G03I-2642J0D01*
G01X152135Y-98681D02*
G03I-632J0D01*
G01X154064Y-110118D02*
G03I-1460J0D01*
G01X154764Y-99775D02*
G03I-892J0D01*
G01X158530Y-88809D02*
G03I-1041J0D01*
G01X161742Y-91601D02*
G03I-1458J0D01*
G01X165531Y-94981D02*
G03I-1869J0D01*
G01X171080Y-131739D02*
G03I-1282J0D01*
G01X169322Y-135033D02*
G03I-892J0D01*
G01X180669Y-131528D02*
G03I-1870J0D01*
G01X180255Y-136311D02*
G03I-1456J0D01*
G01X179841Y-140261D02*
G03I-1042J0D01*
G01X179433Y-143587D02*
G03I-634J0D01*
G01X181439Y-119680D02*
G03I-2640J0D01*
G01X175373Y-123081D02*
G03I-1968J0D01*
G01X173018Y-127816D02*
G03I-1584J0D01*
G01X174681Y-116876D02*
G03I-2640J0D01*
G01X180979Y-125917D02*
G03I-2180J0D01*
G01X186177Y-123075D02*
G03I-1971J0D01*
G01X188199Y-116876D02*
G03I-2640J0D01*
G01X175452Y-97124D02*
G03I-1968J0D01*
G01X186225Y-97178D02*
G03I-1971J0D01*
G01X181439Y-100556D02*
G03I-2640J0D01*
G01X174681Y-103361D02*
G03I-2640J0D01*
G01X188199D02*
G03I-2640J0D01*
G01X179841Y-79975D02*
G03I-1042J0D01*
G01X171217Y-88444D02*
G03I-1282J0D01*
G01X173123Y-92378D02*
G03I-1584J0D01*
G01X180255Y-83924D02*
G03I-1456J0D01*
G01X180669Y-88708D02*
G03I-1870J0D01*
G01X180979Y-94320D02*
G03I-2180J0D01*
G01X179433Y-76648D02*
G03I-634J0D01*
G01X191096Y-134658D02*
G03I-892J0D01*
G01X192135Y-136781D02*
G03I-631J0D01*
G01X198775Y-128635D02*
G03I-1458J0D01*
G01X195808Y-125255D02*
G03I-1869J0D01*
G01X200547Y-113952D02*
G03X203345Y-117196I7247J3422D01*
G01X192148Y-121285D02*
G03I-2180J0D01*
G01X187928Y-127802D02*
G03I-1584J0D01*
G01X189667Y-131511D02*
G03I-1283J0D01*
G01X200699Y-105836D02*
G03X200547Y-113953I8974J-4228D01*
G01X208284Y-101612D02*
G03X200698Y-105835I-219J-8531D01*
G01X192148Y-98951D02*
G03I-2180J0D01*
G01X191108Y-82727D02*
G03I-634J0D01*
G01X190184Y-85250D02*
G03I-893J0D01*
G01X195808Y-94981D02*
G03I-1869J0D01*
G01X187839Y-92457D02*
G03I-1584J0D01*
G01X189190Y-88538D02*
G03I-1283J0D01*
G01X214259Y-115661D02*
G03X213314Y-114453I-714J415D01*
G01X202049Y-108260D02*
G03X205722Y-116181I7039J-1548D01*
G01X218075Y-112869D02*
G03X219083Y-115752I4343J-99D01*
G01X208854Y-116658D02*
G03X213313Y-114452I-2485J10632D01*
G01X208470Y-118462D02*
G03X214261Y-115663I-1122J9711D01*
G01X203346Y-117195D02*
G03X208470Y-118461I4545J7394D01*
G01X205721Y-116179D02*
G03X208853Y-116659I2561J6250D01*
G01X215903Y-114020D02*
G03X219079Y-118061I6190J1597D01*
G01X215904Y-114020D02*
Y-111835D01*
G01X227413Y-112869D02*
X218074D01*
G01X214175Y-103951D02*
G03X208283Y-101613I-6403J-7542D01*
G01X213150Y-105147D02*
G03X214175Y-103951I410J686D01*
G01X213152Y-105146D02*
G03X208030Y-103430I-5122J-6786D01*
G01X208029Y-103429D02*
G03X202049Y-108259I-48J-6058D01*
G01X225189Y-111399D02*
G03X218071I-3559J159D01*
G01X218070Y-111418D02*
Y-111399D01*
G01X225188Y-111418D02*
X218070D01*
G01X227412Y-111835D02*
G03X215906I-5753J223D01*
G01X230059Y-117625D02*
Y-102034D01*
G01X230060Y-117626D02*
G03X232080I1010J239D01*
G01X226590Y-116472D02*
G03X225311Y-115210I-817J451D01*
G01X234673Y-114020D02*
G03X237849Y-118061I6190J1597D01*
G01X232081Y-102041D02*
Y-117625D01*
G01X219083Y-115753D02*
G03X225311Y-115211I2844J3371D01*
G01X219079Y-118060D02*
G03X226591Y-116473I2662J5972D01*
G01X227413Y-111835D02*
Y-112869D01*
G01X232080Y-102041D02*
G03X230060Y-102034I-1011J-236D01*
G01X225188Y-111399D02*
Y-111418D01*
G01X234675Y-114020D02*
Y-111835D01*
G01X246181D02*
G03X234675I-5753J223D01*
G01X252849Y-116771D02*
G03X254892Y-115895I-74J2994D01*
G01X236844Y-112869D02*
G03X237852Y-115752I4343J-99D01*
G01X237848Y-118060D02*
G03X245360Y-116473I2662J5972D01*
G01X245358Y-116472D02*
G03X244079Y-115210I-817J451D01*
G01X237852Y-115753D02*
G03X244080Y-115211I2844J3371D01*
G01X249566Y-115529D02*
G03X252307Y-116760I2985J2980D01*
G01Y-116761D02*
G03X252849Y-116772I366J4691D01*
G01X250282Y-118087D02*
G03X254318Y-118340I2605J9244D01*
G01X247897Y-116444D02*
G03X250283Y-118086I3752J2898D01*
G01X249568Y-115529D02*
G03X247898Y-116443I-748J-616D01*
G01X255608Y-108618D02*
G03X253612Y-107689I-3116J-4086D01*
G01X246181Y-111835D02*
Y-112869D01*
G01D02*
X236844D01*
G01X255002Y-114328D02*
G03X252723Y-112986I-3540J-3405D01*
G01X249955Y-112030D02*
G03X252723Y-112985I8208J19302D01*
G01X243957Y-111399D02*
Y-111418D01*
G01X243958Y-111399D02*
G03X236840I-3559J159D01*
G01X236841Y-111418D02*
Y-111399D01*
G01X243957Y-111418D02*
X236841D01*
G01X248537Y-109748D02*
G03X249956Y-112031I2652J66D01*
G01X248537Y-108250D02*
Y-109748D01*
G01X250179Y-106359D02*
G03X248537Y-108249I2747J-4045D01*
G01X256884Y-107368D02*
G03X250178Y-106359I-4153J-4811D01*
G01X253611Y-107689D02*
G03X251080Y-107949I-869J-3992D01*
G01X251081Y-107948D02*
G03X250837Y-110104I805J-1183D01*
G01Y-110106D02*
G03X254306Y-111513I5270J8013D01*
G01X260954Y-116041D02*
Y-107954D01*
G01X254892Y-115895D02*
G03X255001Y-114328I-764J840D01*
G01X269619Y-117484D02*
Y-106797D01*
G01X269620Y-117484D02*
G03X271926I1153J198D01*
G01X266864Y-117375D02*
G03X266002Y-116329I-764J249D01*
G01X262978Y-115462D02*
G03X266002Y-116329I2046J1428D01*
G01X260955Y-116043D02*
G03X264164Y-118351I2956J725D01*
G01X265463Y-118350D02*
X264165D01*
G01X265464Y-118352D02*
G03X266864Y-117374I-24J1525D01*
G01X256906Y-116470D02*
G03X257054Y-113728I-3143J1545D01*
G01X254317Y-118340D02*
G03X256906Y-116470I-1259J4470D01*
G01X262978Y-107954D02*
Y-115463D01*
G01X257054Y-113729D02*
G03X254307Y-111513I-3470J-1490D01*
G01X271969Y-102342D02*
G03I-1194J0D01*
G01X271926Y-106797D02*
G03X269620I-1153J-409D01*
G01X266003Y-107954D02*
X262978D01*
G01X266004Y-107955D02*
G03X266008Y-105932I-177J1012D01*
G01X262978D02*
X266008D01*
G01X262971Y-103419D02*
X262978Y-105932D01*
G01X262972Y-103418D02*
G03X260954Y-103491I-1005J-141D01*
G01Y-105932D02*
Y-103492D01*
G01X259930Y-105932D02*
X260954D01*
G01X259930D02*
G03X259981Y-107955I298J-1005D01*
G01X260954Y-107954D02*
X259982D01*
G01X255606Y-108620D02*
G03X256885Y-107367I599J667D01*
G01X290671Y-110842D02*
G03X290703Y-118351I860J-3751D01*
G01X276837Y-114305D02*
G03X278891Y-116297I4069J2141D01*
G01X274529Y-113568D02*
G03X275888Y-116443I5718J944D01*
G01X275887D02*
G03X279572Y-118352I4392J3967D01*
G01X281425Y-118350D02*
X279571D01*
G01X281425D02*
G03X284525Y-117161I0J4636D01*
G01X285201Y-116508D02*
X284524Y-117161D01*
G01X285201Y-116508D02*
G03X283966Y-115211I-695J574D01*
G01X281510Y-116675D02*
G03X283966Y-115212I-989J4453D01*
G01X278889Y-116297D02*
G03X281508Y-116677I1946J4197D01*
G01X271926Y-106797D02*
Y-117484D01*
G01X274529Y-113566D02*
Y-111839D01*
G01X276446Y-112943D02*
G03X276837Y-114305I4162J458D01*
G01X276445Y-112066D02*
Y-112943D01*
G01X283833Y-109274D02*
G03X285403Y-108106I585J852D01*
G01X285402D02*
G03X280919Y-105777I-4776J-3714D01*
G01X279541D02*
X280919D01*
G01X279540D02*
G03X274999Y-109274I1260J-6333D01*
G01X274998D02*
G03X274529Y-111839I9988J-3152D01*
G01X276849Y-109932D02*
G03X276446Y-112066I5467J-2137D01*
G01X280036Y-107542D02*
G03X276849Y-109933I664J-4205D01*
G01X282662Y-108199D02*
G03X280037Y-107539I-2313J-3650D01*
G01X283833Y-109275D02*
G03X282662Y-108202I-9277J-8949D01*
G01X294457Y-116619D02*
G03Y-112289I-51J2165D01*
G01X291853Y-116620D02*
X294456D01*
G01X291853Y-112289D02*
G03Y-116619I195J-2165D01*
G01X294165Y-118350D02*
X290701D01*
G01X294165D02*
G03X296471Y-117226I-1088J5161D01*
G01X296473Y-117625D02*
Y-117226D01*
G01X296474Y-117627D02*
G03X298494I1010J185D01*
G01X298495Y-109394D02*
Y-117625D01*
G01X301067Y-108534D02*
Y-106508D01*
G01X301615Y-108534D02*
X301067D01*
G01X301615Y-106508D02*
Y-108534D01*
G01X302461Y-106508D02*
X301615D01*
G01X302461Y-106001D02*
Y-106508D01*
G01X300223Y-106001D02*
X302461D01*
G01X300223Y-106508D02*
Y-106001D01*
G01X301067Y-106508D02*
X300223D01*
G01X305164Y-106001D02*
X304731D01*
G01X305713Y-108544D02*
X305164Y-106001D01*
G01X305171Y-108544D02*
X305713D01*
G01X304889Y-106871D02*
X305171Y-108544D01*
G01X304309D02*
X304889Y-106871D01*
G01X304086Y-108544D02*
X304309D01*
G01X303501Y-106887D02*
X304086Y-108544D01*
G01X303226D02*
X303501Y-106887D01*
G01X302698Y-108544D02*
X303226D01*
G01X303243Y-106001D02*
X302698Y-108544D01*
G01X303648Y-106001D02*
X303243D01*
G01X304192Y-107632D02*
X303648Y-106001D01*
G01X304731D02*
X304192Y-107632D01*
G01X294456Y-112288D02*
X291853D01*
G01X296473Y-110841D02*
Y-109686D01*
G01X296472Y-110841D02*
G03X292878Y-110536I-3256J-17043D01*
G01X292879Y-110535D02*
G03X290670Y-110842I280J-10112D01*
G01X298496Y-109394D02*
G03X295031Y-105933I-3962J-501D01*
G01X291563Y-105932D02*
X295031D01*
G01X291562D02*
G03X289112Y-107085I584J-4421D01*
G01Y-107086D02*
G03X289820Y-108520I585J-603D01*
G01X290987Y-107954D02*
G03X289821Y-108520I1446J-4464D01*
G01X294740Y-107954D02*
X290987D01*
G01X296473Y-109686D02*
G03X294742Y-107955I-1598J133D01*
G54D39*
X567550Y263750D03*
Y272450D03*
X567050Y300950D03*
Y292250D03*
X575050Y272450D03*
X574550Y300950D03*
M02*
